FILE_TYPE = MACRO_DRAWING;
SET COLOR_WIRE YELLOW;
SET COLOR_PROP ORANGE;
SET COLOR_DOT WHITE;
SET COLOR_ARC YELLOW;
SET COLOR_BODY GREEN;
SET COLOR_NOTE PURPLE;
SET PROP_DISPLAY VALUE;
SET PAGE_NUMBER P69;
FORCEADD Q_CAP..1
(-9075 875);
FORCEPROP 1 LAST LOCATION C3925
J 0
(-9025 975);
DISPLAY 0.489362 (-9025 975);
PAINT SKYBLUE (-9025 975);
FORCEPROP 2 LAST $SEC 1
J 0
(-9025 1075);
DISPLAY 0.680851 (-9025 1075);
PAINT MONO (-9025 1075);
DISPLAY INVISIBLE (-9025 1075);
FORCEPROP 2 LAST CDS_SEC 1
J 0
(-9025 1075);
DISPLAY 1.021277 (-9025 1075);
DISPLAY INVISIBLE (-9025 1075);
FORCEPROP 1 LASTPIN (-9075 975) $PN 1
J 0
(-9065 955);
DISPLAY 0.489362 (-9065 955);
FORCEPROP 1 LASTPIN (-9075 775) $PN 2
J 0
(-9065 755);
DISPLAY 0.489362 (-9065 755);
FORCEPROP 1 LAST MATERIAL X6S
J 0
(-9025 775);
DISPLAY 0.489362 (-9025 775);
PAINT SKYBLUE (-9025 775);
FORCEPROP 1 LAST TOLERANCE 20%
J 0
(-9025 825);
DISPLAY 0.489362 (-9025 825);
PAINT SKYBLUE (-9025 825);
FORCEPROP 1 LAST VALUE 22UF
J 0
(-9025 925);
DISPLAY 0.489362 (-9025 925);
PAINT SKYBLUE (-9025 925);
FORCEPROP 1 LAST PART_NUMBER CH622KMEB02
J 0
(-9025 725);
DISPLAY 0.489362 (-9025 725);
PAINT SKYBLUE (-9025 725);
FORCEPROP 1 LAST VOLTAGE 4V
J 0
(-9025 875);
DISPLAY 0.489362 (-9025 875);
PAINT SKYBLUE (-9025 875);
FORCEPROP 1 LAST PACK_TYPE C0402
J 0
(-9025 675);
DISPLAY 0.489362 (-9025 675);
PAINT SKYBLUE (-9025 675);
FORCEPROP 2 LAST CDS_LIB pure_quanta
J 0
(-9075 875);
PAINT MONO (-9075 875);
DISPLAY INVISIBLE (-9075 875);
FORCEPROP 1 LAST PATH I1
J 0
(-9025 1025);
DISPLAY 0.978723 (-9025 1025);
PAINT WHITE (-9025 1025);
DISPLAY INVISIBLE (-9025 1025);
FORCEADD Q_CAP..1
(-8625 2300);
FORCEPROP 1 LAST LOCATION C2539
J 0
(-8575 2400);
DISPLAY 0.489362 (-8575 2400);
PAINT SKYBLUE (-8575 2400);
FORCEPROP 2 LAST $SEC 1
J 0
(-8575 2500);
DISPLAY 0.680851 (-8575 2500);
PAINT MONO (-8575 2500);
DISPLAY INVISIBLE (-8575 2500);
FORCEPROP 2 LAST CDS_SEC 1
J 0
(-8575 2500);
DISPLAY 1.021277 (-8575 2500);
DISPLAY INVISIBLE (-8575 2500);
FORCEPROP 1 LASTPIN (-8625 2400) $PN 1
J 0
(-8615 2380);
DISPLAY 0.489362 (-8615 2380);
FORCEPROP 1 LASTPIN (-8625 2200) $PN 2
J 0
(-8615 2180);
DISPLAY 0.489362 (-8615 2180);
FORCEPROP 1 LAST MATERIAL X6S
J 0
(-8575 2200);
DISPLAY 0.489362 (-8575 2200);
PAINT SKYBLUE (-8575 2200);
FORCEPROP 1 LAST TOLERANCE 20%
J 0
(-8575 2250);
DISPLAY 0.489362 (-8575 2250);
PAINT SKYBLUE (-8575 2250);
FORCEPROP 1 LAST VALUE 22UF
J 0
(-8575 2350);
DISPLAY 0.489362 (-8575 2350);
PAINT SKYBLUE (-8575 2350);
FORCEPROP 1 LAST PART_NUMBER CH622KMEB02
J 0
(-8575 2150);
DISPLAY 0.489362 (-8575 2150);
PAINT SKYBLUE (-8575 2150);
FORCEPROP 1 LAST VOLTAGE 4V
J 0
(-8575 2300);
DISPLAY 0.489362 (-8575 2300);
PAINT SKYBLUE (-8575 2300);
FORCEPROP 1 LAST PACK_TYPE C0402
J 0
(-8575 2100);
DISPLAY 0.489362 (-8575 2100);
PAINT SKYBLUE (-8575 2100);
FORCEPROP 2 LAST CDS_LIB pure_quanta
J 0
(-8625 2300);
PAINT MONO (-8625 2300);
DISPLAY INVISIBLE (-8625 2300);
FORCEPROP 1 LAST PATH I10
J 0
(-8575 2450);
DISPLAY 0.978723 (-8575 2450);
PAINT WHITE (-8575 2450);
DISPLAY INVISIBLE (-8575 2450);
FORCEADD UNIVERSAL_GND..1
(-5100 4775);
FORCEPROP 3 LASTPIN (-5100 4825) SIG_NAME GND\g
J 0
(-5090 4835);
DISPLAY 0.659574 (-5090 4835);
PAINT MONO (-5090 4835);
DISPLAY INVISIBLE (-5090 4835);
FORCEPROP 2 LAST CDS_LIB pure_quanta_power
J 0
(-5100 4775);
PAINT MONO (-5100 4775);
DISPLAY INVISIBLE (-5100 4775);
FORCEPROP 1 LAST PATH I100
J 0
(-5025 4775);
DISPLAY 0.872340 (-5025 4775);
PAINT AQUA (-5025 4775);
DISPLAY INVISIBLE (-5025 4775);
FORCEPROP 1 LAST HDL_POWER GND
J 1
(-5075 4700);
DISPLAY 0.872340 (-5075 4700);
PAINT GREEN (-5075 4700);
DISPLAY INVISIBLE (-5075 4700);
FORCEADD Q_CAP..1
(-5100 5150);
FORCEPROP 1 LAST LOCATION C2591
J 0
(-5050 5250);
DISPLAY 0.489362 (-5050 5250);
PAINT SKYBLUE (-5050 5250);
FORCEPROP 2 LAST $SEC 1
J 0
(-5050 5350);
DISPLAY 0.680851 (-5050 5350);
PAINT MONO (-5050 5350);
DISPLAY INVISIBLE (-5050 5350);
FORCEPROP 2 LAST CDS_SEC 1
J 0
(-5050 5350);
DISPLAY 1.021277 (-5050 5350);
DISPLAY INVISIBLE (-5050 5350);
FORCEPROP 1 LASTPIN (-5100 5250) $PN 1
J 0
(-5090 5230);
DISPLAY 0.489362 (-5090 5230);
FORCEPROP 1 LASTPIN (-5100 5050) $PN 2
J 0
(-5090 5030);
DISPLAY 0.489362 (-5090 5030);
FORCEPROP 1 LAST MATERIAL X6S
J 0
(-5050 5050);
DISPLAY 0.489362 (-5050 5050);
PAINT SKYBLUE (-5050 5050);
FORCEPROP 1 LAST TOLERANCE 20%
J 0
(-5050 5100);
DISPLAY 0.489362 (-5050 5100);
PAINT SKYBLUE (-5050 5100);
FORCEPROP 1 LAST VALUE 22UF
J 0
(-5050 5200);
DISPLAY 0.489362 (-5050 5200);
PAINT SKYBLUE (-5050 5200);
FORCEPROP 1 LAST PART_NUMBER CH622KMEB02
J 0
(-5050 5000);
DISPLAY 0.489362 (-5050 5000);
PAINT SKYBLUE (-5050 5000);
FORCEPROP 1 LAST VOLTAGE 4V
J 0
(-5050 5150);
DISPLAY 0.489362 (-5050 5150);
PAINT SKYBLUE (-5050 5150);
FORCEPROP 1 LAST PACK_TYPE C0402
J 0
(-5050 4950);
DISPLAY 0.489362 (-5050 4950);
PAINT SKYBLUE (-5050 4950);
FORCEPROP 2 LAST CDS_LIB pure_quanta
J 0
(-5100 5150);
PAINT MONO (-5100 5150);
DISPLAY INVISIBLE (-5100 5150);
FORCEPROP 1 LAST PATH I101
J 0
(-5050 5300);
DISPLAY 0.978723 (-5050 5300);
PAINT WHITE (-5050 5300);
DISPLAY INVISIBLE (-5050 5300);
FORCEADD Q_CAP..1
(-4500 4325);
FORCEPROP 1 LAST LOCATION C2599
J 0
(-4450 4425);
DISPLAY 0.489362 (-4450 4425);
PAINT SKYBLUE (-4450 4425);
FORCEPROP 2 LAST $SEC 1
J 0
(-4450 4525);
DISPLAY 0.680851 (-4450 4525);
PAINT MONO (-4450 4525);
DISPLAY INVISIBLE (-4450 4525);
FORCEPROP 2 LAST CDS_SEC 1
J 0
(-4450 4525);
DISPLAY 1.021277 (-4450 4525);
DISPLAY INVISIBLE (-4450 4525);
FORCEPROP 1 LASTPIN (-4500 4425) $PN 1
J 0
(-4490 4405);
DISPLAY 0.489362 (-4490 4405);
FORCEPROP 1 LASTPIN (-4500 4225) $PN 2
J 0
(-4490 4205);
DISPLAY 0.489362 (-4490 4205);
FORCEPROP 1 LAST MATERIAL X6S
J 0
(-4450 4225);
DISPLAY 0.489362 (-4450 4225);
PAINT SKYBLUE (-4450 4225);
FORCEPROP 1 LAST TOLERANCE 20%
J 0
(-4450 4275);
DISPLAY 0.489362 (-4450 4275);
PAINT SKYBLUE (-4450 4275);
FORCEPROP 1 LAST VALUE 22UF
J 0
(-4450 4375);
DISPLAY 0.489362 (-4450 4375);
PAINT SKYBLUE (-4450 4375);
FORCEPROP 1 LAST PART_NUMBER CH622KMEB02
J 0
(-4450 4175);
DISPLAY 0.489362 (-4450 4175);
PAINT SKYBLUE (-4450 4175);
FORCEPROP 1 LAST VOLTAGE 4V
J 0
(-4450 4325);
DISPLAY 0.489362 (-4450 4325);
PAINT SKYBLUE (-4450 4325);
FORCEPROP 1 LAST PACK_TYPE C0402
J 0
(-4450 4125);
DISPLAY 0.489362 (-4450 4125);
PAINT SKYBLUE (-4450 4125);
FORCEPROP 2 LAST CDS_LIB pure_quanta
J 0
(-4500 4325);
PAINT MONO (-4500 4325);
DISPLAY INVISIBLE (-4500 4325);
FORCEPROP 1 LAST PATH I102
J 0
(-4450 4475);
DISPLAY 0.978723 (-4450 4475);
PAINT WHITE (-4450 4475);
DISPLAY INVISIBLE (-4450 4475);
FORCEADD UNIVERSAL_POWER..1
(-4500 4600);
FORCEPROP 3 LASTPIN (-4500 4550) SIG_NAME PVDDIO_P0\g
J 0
(-4490 4560);
DISPLAY 0.659574 (-4490 4560);
PAINT MONO (-4490 4560);
DISPLAY INVISIBLE (-4490 4560);
FORCEPROP 1 LAST HDL_POWER PVDDIO_P0
J 1
(-4500 4650);
DISPLAY 0.489362 (-4500 4650);
PAINT GREEN (-4500 4650);
FORCEPROP 2 LAST CDS_LIB pure_quanta_power
J 0
(-4500 4600);
DISPLAY INVISIBLE (-4500 4600);
FORCEPROP 1 LAST PATH I103
J 0
(-4450 4625);
DISPLAY 0.872340 (-4450 4625);
PAINT AQUA (-4450 4625);
DISPLAY INVISIBLE (-4450 4625);
FORCEADD Q_CAP..1
(-4525 5100);
FORCEPROP 1 LAST LOCATION C2598
J 0
(-4475 5200);
DISPLAY 0.489362 (-4475 5200);
PAINT SKYBLUE (-4475 5200);
FORCEPROP 2 LAST $SEC 1
J 0
(-4475 5300);
DISPLAY 0.680851 (-4475 5300);
PAINT MONO (-4475 5300);
DISPLAY INVISIBLE (-4475 5300);
FORCEPROP 2 LAST CDS_SEC 1
J 0
(-4475 5300);
DISPLAY 1.021277 (-4475 5300);
DISPLAY INVISIBLE (-4475 5300);
FORCEPROP 1 LASTPIN (-4525 5200) $PN 1
J 0
(-4515 5180);
DISPLAY 0.489362 (-4515 5180);
FORCEPROP 1 LASTPIN (-4525 5000) $PN 2
J 0
(-4515 4980);
DISPLAY 0.489362 (-4515 4980);
FORCEPROP 1 LAST MATERIAL X6S
J 0
(-4475 5000);
DISPLAY 0.489362 (-4475 5000);
PAINT SKYBLUE (-4475 5000);
FORCEPROP 1 LAST TOLERANCE 20%
J 0
(-4475 5050);
DISPLAY 0.489362 (-4475 5050);
PAINT SKYBLUE (-4475 5050);
FORCEPROP 1 LAST VALUE 22UF
J 0
(-4475 5150);
DISPLAY 0.489362 (-4475 5150);
PAINT SKYBLUE (-4475 5150);
FORCEPROP 1 LAST PART_NUMBER CH622KMEB02
J 0
(-4475 4950);
DISPLAY 0.489362 (-4475 4950);
PAINT SKYBLUE (-4475 4950);
FORCEPROP 1 LAST VOLTAGE 4V
J 0
(-4475 5100);
DISPLAY 0.489362 (-4475 5100);
PAINT SKYBLUE (-4475 5100);
FORCEPROP 1 LAST PACK_TYPE C0402
J 0
(-4475 4900);
DISPLAY 0.489362 (-4475 4900);
PAINT SKYBLUE (-4475 4900);
FORCEPROP 2 LAST CDS_LIB pure_quanta
J 0
(-4525 5100);
PAINT MONO (-4525 5100);
DISPLAY INVISIBLE (-4525 5100);
FORCEPROP 1 LAST PATH I104
J 0
(-4475 5250);
DISPLAY 0.978723 (-4475 5250);
PAINT WHITE (-4475 5250);
DISPLAY INVISIBLE (-4475 5250);
FORCEADD UNIVERSAL_GND..1
(-5100 5525);
FORCEPROP 3 LASTPIN (-5100 5575) SIG_NAME GND\g
J 0
(-5090 5585);
DISPLAY 0.659574 (-5090 5585);
PAINT MONO (-5090 5585);
DISPLAY INVISIBLE (-5090 5585);
FORCEPROP 2 LAST CDS_LIB pure_quanta_power
J 0
(-5100 5525);
PAINT MONO (-5100 5525);
DISPLAY INVISIBLE (-5100 5525);
FORCEPROP 1 LAST PATH I105
J 0
(-5025 5525);
DISPLAY 0.872340 (-5025 5525);
PAINT AQUA (-5025 5525);
DISPLAY INVISIBLE (-5025 5525);
FORCEPROP 1 LAST HDL_POWER GND
J 1
(-5075 5450);
DISPLAY 0.872340 (-5075 5450);
PAINT GREEN (-5075 5450);
DISPLAY INVISIBLE (-5075 5450);
FORCEADD Q_CAP..1
(-5100 5900);
FORCEPROP 1 LAST LOCATION C2590
J 0
(-5050 6000);
DISPLAY 0.489362 (-5050 6000);
PAINT SKYBLUE (-5050 6000);
FORCEPROP 2 LAST $SEC 1
J 0
(-5050 6100);
DISPLAY 0.680851 (-5050 6100);
PAINT MONO (-5050 6100);
DISPLAY INVISIBLE (-5050 6100);
FORCEPROP 2 LAST CDS_SEC 1
J 0
(-5050 6100);
DISPLAY 1.021277 (-5050 6100);
DISPLAY INVISIBLE (-5050 6100);
FORCEPROP 1 LASTPIN (-5100 6000) $PN 1
J 0
(-5090 5980);
DISPLAY 0.489362 (-5090 5980);
FORCEPROP 1 LASTPIN (-5100 5800) $PN 2
J 0
(-5090 5780);
DISPLAY 0.489362 (-5090 5780);
FORCEPROP 1 LAST MATERIAL X6S
J 0
(-5050 5800);
DISPLAY 0.489362 (-5050 5800);
PAINT SKYBLUE (-5050 5800);
FORCEPROP 1 LAST TOLERANCE 20%
J 0
(-5050 5850);
DISPLAY 0.489362 (-5050 5850);
PAINT SKYBLUE (-5050 5850);
FORCEPROP 1 LAST VALUE 22UF
J 0
(-5050 5950);
DISPLAY 0.489362 (-5050 5950);
PAINT SKYBLUE (-5050 5950);
FORCEPROP 1 LAST PART_NUMBER CH622KMEB02
J 0
(-5050 5750);
DISPLAY 0.489362 (-5050 5750);
PAINT SKYBLUE (-5050 5750);
FORCEPROP 1 LAST VOLTAGE 4V
J 0
(-5050 5900);
DISPLAY 0.489362 (-5050 5900);
PAINT SKYBLUE (-5050 5900);
FORCEPROP 1 LAST PACK_TYPE C0402
J 0
(-5050 5700);
DISPLAY 0.489362 (-5050 5700);
PAINT SKYBLUE (-5050 5700);
FORCEPROP 2 LAST CDS_LIB pure_quanta
J 0
(-5100 5900);
PAINT MONO (-5100 5900);
DISPLAY INVISIBLE (-5100 5900);
FORCEPROP 1 LAST PATH I106
J 0
(-5050 6050);
DISPLAY 0.978723 (-5050 6050);
PAINT WHITE (-5050 6050);
DISPLAY INVISIBLE (-5050 6050);
FORCEADD UNIVERSAL_POWER..1
(-4525 5375);
FORCEPROP 3 LASTPIN (-4525 5325) SIG_NAME PVDDIO_P0\g
J 0
(-4515 5335);
DISPLAY 0.659574 (-4515 5335);
PAINT MONO (-4515 5335);
DISPLAY INVISIBLE (-4515 5335);
FORCEPROP 1 LAST HDL_POWER PVDDIO_P0
J 1
(-4525 5425);
DISPLAY 0.489362 (-4525 5425);
PAINT GREEN (-4525 5425);
FORCEPROP 2 LAST CDS_LIB pure_quanta_power
J 0
(-4525 5375);
DISPLAY INVISIBLE (-4525 5375);
FORCEPROP 1 LAST PATH I107
J 0
(-4475 5400);
DISPLAY 0.872340 (-4475 5400);
PAINT AQUA (-4475 5400);
DISPLAY INVISIBLE (-4475 5400);
FORCEADD Q_CAP..1
(-4525 5900);
FORCEPROP 1 LAST LOCATION C2597
J 0
(-4475 6000);
DISPLAY 0.489362 (-4475 6000);
PAINT SKYBLUE (-4475 6000);
FORCEPROP 2 LAST $SEC 1
J 0
(-4475 6100);
DISPLAY 0.680851 (-4475 6100);
PAINT MONO (-4475 6100);
DISPLAY INVISIBLE (-4475 6100);
FORCEPROP 2 LAST CDS_SEC 1
J 0
(-4475 6100);
DISPLAY 1.021277 (-4475 6100);
DISPLAY INVISIBLE (-4475 6100);
FORCEPROP 1 LASTPIN (-4525 6000) $PN 1
J 0
(-4515 5980);
DISPLAY 0.489362 (-4515 5980);
FORCEPROP 1 LASTPIN (-4525 5800) $PN 2
J 0
(-4515 5780);
DISPLAY 0.489362 (-4515 5780);
FORCEPROP 1 LAST MATERIAL X6S
J 0
(-4475 5800);
DISPLAY 0.489362 (-4475 5800);
PAINT SKYBLUE (-4475 5800);
FORCEPROP 1 LAST TOLERANCE 20%
J 0
(-4475 5850);
DISPLAY 0.489362 (-4475 5850);
PAINT SKYBLUE (-4475 5850);
FORCEPROP 1 LAST VALUE 22UF
J 0
(-4475 5950);
DISPLAY 0.489362 (-4475 5950);
PAINT SKYBLUE (-4475 5950);
FORCEPROP 1 LAST PART_NUMBER CH622KMEB02
J 0
(-4475 5750);
DISPLAY 0.489362 (-4475 5750);
PAINT SKYBLUE (-4475 5750);
FORCEPROP 1 LAST VOLTAGE 4V
J 0
(-4475 5900);
DISPLAY 0.489362 (-4475 5900);
PAINT SKYBLUE (-4475 5900);
FORCEPROP 1 LAST PACK_TYPE C0402
J 0
(-4475 5700);
DISPLAY 0.489362 (-4475 5700);
PAINT SKYBLUE (-4475 5700);
FORCEPROP 2 LAST CDS_LIB pure_quanta
J 0
(-4525 5900);
PAINT MONO (-4525 5900);
DISPLAY INVISIBLE (-4525 5900);
FORCEPROP 1 LAST PATH I108
J 0
(-4475 6050);
DISPLAY 0.978723 (-4475 6050);
PAINT WHITE (-4475 6050);
DISPLAY INVISIBLE (-4475 6050);
FORCEADD UNIVERSAL_POWER..1
(-4525 6175);
FORCEPROP 3 LASTPIN (-4525 6125) SIG_NAME PVDDIO_P0\g
J 0
(-4515 6135);
DISPLAY 0.659574 (-4515 6135);
PAINT MONO (-4515 6135);
DISPLAY INVISIBLE (-4515 6135);
FORCEPROP 1 LAST HDL_POWER PVDDIO_P0
J 1
(-4525 6225);
DISPLAY 0.489362 (-4525 6225);
PAINT GREEN (-4525 6225);
FORCEPROP 2 LAST CDS_LIB pure_quanta_power
J 0
(-4525 6175);
DISPLAY INVISIBLE (-4525 6175);
FORCEPROP 1 LAST PATH I109
J 0
(-4475 6200);
DISPLAY 0.872340 (-4475 6200);
PAINT AQUA (-4475 6200);
DISPLAY INVISIBLE (-4475 6200);
FORCEADD Q_CAP..1
(-8625 3000);
FORCEPROP 1 LAST LOCATION C2538
J 0
(-8575 3100);
DISPLAY 0.489362 (-8575 3100);
PAINT SKYBLUE (-8575 3100);
FORCEPROP 2 LAST $SEC 1
J 0
(-8575 3200);
DISPLAY 0.680851 (-8575 3200);
PAINT MONO (-8575 3200);
DISPLAY INVISIBLE (-8575 3200);
FORCEPROP 2 LAST CDS_SEC 1
J 0
(-8575 3200);
DISPLAY 1.021277 (-8575 3200);
DISPLAY INVISIBLE (-8575 3200);
FORCEPROP 1 LASTPIN (-8625 3100) $PN 1
J 0
(-8615 3080);
DISPLAY 0.489362 (-8615 3080);
FORCEPROP 1 LASTPIN (-8625 2900) $PN 2
J 0
(-8615 2880);
DISPLAY 0.489362 (-8615 2880);
FORCEPROP 1 LAST MATERIAL X6S
J 0
(-8575 2900);
DISPLAY 0.489362 (-8575 2900);
PAINT SKYBLUE (-8575 2900);
FORCEPROP 1 LAST TOLERANCE 20%
J 0
(-8575 2950);
DISPLAY 0.489362 (-8575 2950);
PAINT SKYBLUE (-8575 2950);
FORCEPROP 1 LAST VALUE 22UF
J 0
(-8575 3050);
DISPLAY 0.489362 (-8575 3050);
PAINT SKYBLUE (-8575 3050);
FORCEPROP 1 LAST PART_NUMBER CH622KMEB02
J 0
(-8575 2850);
DISPLAY 0.489362 (-8575 2850);
PAINT SKYBLUE (-8575 2850);
FORCEPROP 1 LAST VOLTAGE 4V
J 0
(-8575 3000);
DISPLAY 0.489362 (-8575 3000);
PAINT SKYBLUE (-8575 3000);
FORCEPROP 1 LAST PACK_TYPE C0402
J 0
(-8575 2800);
DISPLAY 0.489362 (-8575 2800);
PAINT SKYBLUE (-8575 2800);
FORCEPROP 2 LAST CDS_LIB pure_quanta
J 0
(-8625 3000);
PAINT MONO (-8625 3000);
DISPLAY INVISIBLE (-8625 3000);
FORCEPROP 1 LAST PATH I11
J 0
(-8575 3150);
DISPLAY 0.978723 (-8575 3150);
PAINT WHITE (-8575 3150);
DISPLAY INVISIBLE (-8575 3150);
FORCEADD UNIVERSAL_GND..1
(-4050 475);
FORCEPROP 3 LASTPIN (-4050 525) SIG_NAME GND\g
J 0
(-4040 535);
DISPLAY 0.659574 (-4040 535);
PAINT MONO (-4040 535);
DISPLAY INVISIBLE (-4040 535);
FORCEPROP 2 LAST CDS_LIB pure_quanta_power
J 0
(-4050 475);
DISPLAY INVISIBLE (-4050 475);
FORCEPROP 1 LAST PATH I110
J 0
(-3975 475);
DISPLAY 0.872340 (-3975 475);
PAINT AQUA (-3975 475);
DISPLAY INVISIBLE (-3975 475);
FORCEPROP 1 LAST HDL_POWER GND
J 1
(-4025 400);
DISPLAY 0.872340 (-4025 400);
PAINT GREEN (-4025 400);
DISPLAY INVISIBLE (-4025 400);
FORCEADD Q_CAP..1
(-4050 800);
FORCEPROP 1 LAST LOCATION C3933
J 0
(-4000 900);
DISPLAY 0.489362 (-4000 900);
PAINT SKYBLUE (-4000 900);
FORCEPROP 2 LAST $SEC 1
J 0
(-4000 1000);
DISPLAY 0.680851 (-4000 1000);
PAINT MONO (-4000 1000);
DISPLAY INVISIBLE (-4000 1000);
FORCEPROP 2 LAST CDS_SEC 1
J 0
(-4000 1000);
DISPLAY 1.021277 (-4000 1000);
DISPLAY INVISIBLE (-4000 1000);
FORCEPROP 1 LASTPIN (-4050 900) $PN 1
J 0
(-4040 880);
DISPLAY 0.489362 (-4040 880);
FORCEPROP 1 LASTPIN (-4050 700) $PN 2
J 0
(-4040 680);
DISPLAY 0.489362 (-4040 680);
FORCEPROP 1 LAST MATERIAL X6S
J 0
(-4000 700);
DISPLAY 0.489362 (-4000 700);
PAINT SKYBLUE (-4000 700);
FORCEPROP 1 LAST TOLERANCE 20%
J 0
(-4000 750);
DISPLAY 0.489362 (-4000 750);
PAINT SKYBLUE (-4000 750);
FORCEPROP 1 LAST VALUE 22UF
J 0
(-4000 850);
DISPLAY 0.489362 (-4000 850);
PAINT SKYBLUE (-4000 850);
FORCEPROP 1 LAST PART_NUMBER CH622KMEB02
J 0
(-4000 650);
DISPLAY 0.489362 (-4000 650);
PAINT SKYBLUE (-4000 650);
FORCEPROP 1 LAST VOLTAGE 4V
J 0
(-4000 800);
DISPLAY 0.489362 (-4000 800);
PAINT SKYBLUE (-4000 800);
FORCEPROP 1 LAST PACK_TYPE C0402
J 0
(-4000 600);
DISPLAY 0.489362 (-4000 600);
PAINT SKYBLUE (-4000 600);
FORCEPROP 2 LAST CDS_LIB pure_quanta
J 0
(-4050 800);
PAINT MONO (-4050 800);
DISPLAY INVISIBLE (-4050 800);
FORCEPROP 1 LAST PATH I111
J 0
(-4000 950);
DISPLAY 0.978723 (-4000 950);
PAINT WHITE (-4000 950);
DISPLAY INVISIBLE (-4000 950);
FORCEADD Q_CAP..1
(-4050 1400);
FORCEPROP 1 LAST LOCATION C2610
J 0
(-4000 1500);
DISPLAY 0.489362 (-4000 1500);
PAINT SKYBLUE (-4000 1500);
FORCEPROP 2 LAST $SEC 1
J 0
(-4000 1600);
DISPLAY 0.680851 (-4000 1600);
PAINT MONO (-4000 1600);
DISPLAY INVISIBLE (-4000 1600);
FORCEPROP 2 LAST CDS_SEC 1
J 0
(-4000 1600);
DISPLAY 1.021277 (-4000 1600);
DISPLAY INVISIBLE (-4000 1600);
FORCEPROP 1 LASTPIN (-4050 1500) $PN 1
J 0
(-4040 1480);
DISPLAY 0.489362 (-4040 1480);
FORCEPROP 1 LASTPIN (-4050 1300) $PN 2
J 0
(-4040 1280);
DISPLAY 0.489362 (-4040 1280);
FORCEPROP 1 LAST MATERIAL X6S
J 0
(-4000 1300);
DISPLAY 0.489362 (-4000 1300);
PAINT SKYBLUE (-4000 1300);
FORCEPROP 1 LAST TOLERANCE 20%
J 0
(-4000 1350);
DISPLAY 0.489362 (-4000 1350);
PAINT SKYBLUE (-4000 1350);
FORCEPROP 1 LAST VALUE 22UF
J 0
(-4000 1450);
DISPLAY 0.489362 (-4000 1450);
PAINT SKYBLUE (-4000 1450);
FORCEPROP 1 LAST PART_NUMBER CH622KMEB02
J 0
(-4000 1250);
DISPLAY 0.489362 (-4000 1250);
PAINT SKYBLUE (-4000 1250);
FORCEPROP 1 LAST VOLTAGE 4V
J 0
(-4000 1400);
DISPLAY 0.489362 (-4000 1400);
PAINT SKYBLUE (-4000 1400);
FORCEPROP 1 LAST PACK_TYPE C0402
J 0
(-4000 1200);
DISPLAY 0.489362 (-4000 1200);
PAINT SKYBLUE (-4000 1200);
FORCEPROP 2 LAST CDS_LIB pure_quanta
J 0
(-4050 1400);
PAINT MONO (-4050 1400);
DISPLAY INVISIBLE (-4050 1400);
FORCEPROP 1 LAST PATH I112
J 0
(-4000 1550);
DISPLAY 0.978723 (-4000 1550);
PAINT WHITE (-4000 1550);
DISPLAY INVISIBLE (-4000 1550);
FORCEADD Q_CAP..1
(-4050 2000);
FORCEPROP 1 LAST LOCATION C2609
J 0
(-4000 2100);
DISPLAY 0.489362 (-4000 2100);
PAINT SKYBLUE (-4000 2100);
FORCEPROP 2 LAST $SEC 1
J 0
(-4000 2200);
DISPLAY 0.680851 (-4000 2200);
PAINT MONO (-4000 2200);
DISPLAY INVISIBLE (-4000 2200);
FORCEPROP 2 LAST CDS_SEC 1
J 0
(-4000 2200);
DISPLAY 1.021277 (-4000 2200);
DISPLAY INVISIBLE (-4000 2200);
FORCEPROP 1 LASTPIN (-4050 2100) $PN 1
J 0
(-4040 2080);
DISPLAY 0.489362 (-4040 2080);
FORCEPROP 1 LASTPIN (-4050 1900) $PN 2
J 0
(-4040 1880);
DISPLAY 0.489362 (-4040 1880);
FORCEPROP 1 LAST MATERIAL X6S
J 0
(-4000 1900);
DISPLAY 0.489362 (-4000 1900);
PAINT SKYBLUE (-4000 1900);
FORCEPROP 1 LAST TOLERANCE 20%
J 0
(-4000 1950);
DISPLAY 0.489362 (-4000 1950);
PAINT SKYBLUE (-4000 1950);
FORCEPROP 1 LAST VALUE 22UF
J 0
(-4000 2050);
DISPLAY 0.489362 (-4000 2050);
PAINT SKYBLUE (-4000 2050);
FORCEPROP 1 LAST PART_NUMBER CH622KMEB02
J 0
(-4000 1850);
DISPLAY 0.489362 (-4000 1850);
PAINT SKYBLUE (-4000 1850);
FORCEPROP 1 LAST VOLTAGE 4V
J 0
(-4000 2000);
DISPLAY 0.489362 (-4000 2000);
PAINT SKYBLUE (-4000 2000);
FORCEPROP 1 LAST PACK_TYPE C0402
J 0
(-4000 1800);
DISPLAY 0.489362 (-4000 1800);
PAINT SKYBLUE (-4000 1800);
FORCEPROP 2 LAST CDS_LIB pure_quanta
J 0
(-4050 2000);
PAINT MONO (-4050 2000);
DISPLAY INVISIBLE (-4050 2000);
FORCEPROP 1 LAST PATH I113
J 0
(-4000 2150);
DISPLAY 0.978723 (-4000 2150);
PAINT WHITE (-4000 2150);
DISPLAY INVISIBLE (-4000 2150);
FORCEADD Q_CAP..1
(-3600 1400);
FORCEPROP 1 LAST LOCATION C2617
J 0
(-3550 1500);
DISPLAY 0.489362 (-3550 1500);
PAINT SKYBLUE (-3550 1500);
FORCEPROP 2 LAST $SEC 1
J 0
(-3550 1600);
DISPLAY 0.680851 (-3550 1600);
PAINT MONO (-3550 1600);
DISPLAY INVISIBLE (-3550 1600);
FORCEPROP 2 LAST CDS_SEC 1
J 0
(-3550 1600);
DISPLAY 1.021277 (-3550 1600);
DISPLAY INVISIBLE (-3550 1600);
FORCEPROP 1 LASTPIN (-3600 1500) $PN 1
J 0
(-3590 1480);
DISPLAY 0.489362 (-3590 1480);
FORCEPROP 1 LASTPIN (-3600 1300) $PN 2
J 0
(-3590 1280);
DISPLAY 0.489362 (-3590 1280);
FORCEPROP 1 LAST MATERIAL X6S
J 0
(-3550 1300);
DISPLAY 0.489362 (-3550 1300);
PAINT SKYBLUE (-3550 1300);
FORCEPROP 1 LAST TOLERANCE 20%
J 0
(-3550 1350);
DISPLAY 0.489362 (-3550 1350);
PAINT SKYBLUE (-3550 1350);
FORCEPROP 1 LAST VALUE 22UF
J 0
(-3550 1450);
DISPLAY 0.489362 (-3550 1450);
PAINT SKYBLUE (-3550 1450);
FORCEPROP 1 LAST PART_NUMBER CH622KMEB02
J 0
(-3550 1250);
DISPLAY 0.489362 (-3550 1250);
PAINT SKYBLUE (-3550 1250);
FORCEPROP 1 LAST VOLTAGE 4V
J 0
(-3550 1400);
DISPLAY 0.489362 (-3550 1400);
PAINT SKYBLUE (-3550 1400);
FORCEPROP 1 LAST PACK_TYPE C0402
J 0
(-3550 1200);
DISPLAY 0.489362 (-3550 1200);
PAINT SKYBLUE (-3550 1200);
FORCEPROP 2 LAST CDS_LIB pure_quanta
J 0
(-3600 1400);
PAINT MONO (-3600 1400);
DISPLAY INVISIBLE (-3600 1400);
FORCEPROP 1 LAST PATH I114
J 0
(-3550 1550);
DISPLAY 0.978723 (-3550 1550);
PAINT WHITE (-3550 1550);
DISPLAY INVISIBLE (-3550 1550);
FORCEADD Q_CAP..1
(-3600 2000);
FORCEPROP 1 LAST LOCATION C2616
J 0
(-3550 2100);
DISPLAY 0.489362 (-3550 2100);
PAINT SKYBLUE (-3550 2100);
FORCEPROP 2 LAST $SEC 1
J 0
(-3550 2200);
DISPLAY 0.680851 (-3550 2200);
PAINT MONO (-3550 2200);
DISPLAY INVISIBLE (-3550 2200);
FORCEPROP 2 LAST CDS_SEC 1
J 0
(-3550 2200);
DISPLAY 1.021277 (-3550 2200);
DISPLAY INVISIBLE (-3550 2200);
FORCEPROP 1 LASTPIN (-3600 2100) $PN 1
J 0
(-3590 2080);
DISPLAY 0.489362 (-3590 2080);
FORCEPROP 1 LASTPIN (-3600 1900) $PN 2
J 0
(-3590 1880);
DISPLAY 0.489362 (-3590 1880);
FORCEPROP 1 LAST MATERIAL X6S
J 0
(-3550 1900);
DISPLAY 0.489362 (-3550 1900);
PAINT SKYBLUE (-3550 1900);
FORCEPROP 1 LAST TOLERANCE 20%
J 0
(-3550 1950);
DISPLAY 0.489362 (-3550 1950);
PAINT SKYBLUE (-3550 1950);
FORCEPROP 1 LAST VALUE 22UF
J 0
(-3550 2050);
DISPLAY 0.489362 (-3550 2050);
PAINT SKYBLUE (-3550 2050);
FORCEPROP 1 LAST PART_NUMBER CH622KMEB02
J 0
(-3550 1850);
DISPLAY 0.489362 (-3550 1850);
PAINT SKYBLUE (-3550 1850);
FORCEPROP 1 LAST VOLTAGE 4V
J 0
(-3550 2000);
DISPLAY 0.489362 (-3550 2000);
PAINT SKYBLUE (-3550 2000);
FORCEPROP 1 LAST PACK_TYPE C0402
J 0
(-3550 1800);
DISPLAY 0.489362 (-3550 1800);
PAINT SKYBLUE (-3550 1800);
FORCEPROP 2 LAST CDS_LIB pure_quanta
J 0
(-3600 2000);
PAINT MONO (-3600 2000);
DISPLAY INVISIBLE (-3600 2000);
FORCEPROP 1 LAST PATH I115
J 0
(-3550 2150);
DISPLAY 0.978723 (-3550 2150);
PAINT WHITE (-3550 2150);
DISPLAY INVISIBLE (-3550 2150);
FORCEADD Q_CAP..1
(-3150 1400);
FORCEPROP 1 LAST LOCATION C2624
J 0
(-3100 1500);
DISPLAY 0.489362 (-3100 1500);
PAINT SKYBLUE (-3100 1500);
FORCEPROP 2 LAST $SEC 1
J 0
(-3100 1600);
DISPLAY 0.680851 (-3100 1600);
PAINT MONO (-3100 1600);
DISPLAY INVISIBLE (-3100 1600);
FORCEPROP 2 LAST CDS_SEC 1
J 0
(-3100 1600);
DISPLAY 1.021277 (-3100 1600);
DISPLAY INVISIBLE (-3100 1600);
FORCEPROP 1 LASTPIN (-3150 1500) $PN 1
J 0
(-3140 1480);
DISPLAY 0.489362 (-3140 1480);
FORCEPROP 1 LASTPIN (-3150 1300) $PN 2
J 0
(-3140 1280);
DISPLAY 0.489362 (-3140 1280);
FORCEPROP 1 LAST MATERIAL X6S
J 0
(-3100 1300);
DISPLAY 0.489362 (-3100 1300);
PAINT SKYBLUE (-3100 1300);
FORCEPROP 1 LAST TOLERANCE 20%
J 0
(-3100 1350);
DISPLAY 0.489362 (-3100 1350);
PAINT SKYBLUE (-3100 1350);
FORCEPROP 1 LAST VALUE 22UF
J 0
(-3100 1450);
DISPLAY 0.489362 (-3100 1450);
PAINT SKYBLUE (-3100 1450);
FORCEPROP 1 LAST PART_NUMBER CH622KMEB02
J 0
(-3100 1250);
DISPLAY 0.489362 (-3100 1250);
PAINT SKYBLUE (-3100 1250);
FORCEPROP 1 LAST VOLTAGE 4V
J 0
(-3100 1400);
DISPLAY 0.489362 (-3100 1400);
PAINT SKYBLUE (-3100 1400);
FORCEPROP 1 LAST PACK_TYPE C0402
J 0
(-3100 1200);
DISPLAY 0.489362 (-3100 1200);
PAINT SKYBLUE (-3100 1200);
FORCEPROP 2 LAST CDS_LIB pure_quanta
J 0
(-3150 1400);
PAINT MONO (-3150 1400);
DISPLAY INVISIBLE (-3150 1400);
FORCEPROP 1 LAST PATH I116
J 0
(-3100 1550);
DISPLAY 0.978723 (-3100 1550);
PAINT WHITE (-3100 1550);
DISPLAY INVISIBLE (-3100 1550);
FORCEADD Q_CAP..1
(-3150 2000);
FORCEPROP 1 LAST LOCATION C2623
J 0
(-3100 2100);
DISPLAY 0.489362 (-3100 2100);
PAINT SKYBLUE (-3100 2100);
FORCEPROP 2 LAST $SEC 1
J 0
(-3100 2200);
DISPLAY 0.680851 (-3100 2200);
PAINT MONO (-3100 2200);
DISPLAY INVISIBLE (-3100 2200);
FORCEPROP 2 LAST CDS_SEC 1
J 0
(-3100 2200);
DISPLAY 1.021277 (-3100 2200);
DISPLAY INVISIBLE (-3100 2200);
FORCEPROP 1 LASTPIN (-3150 2100) $PN 1
J 0
(-3140 2080);
DISPLAY 0.489362 (-3140 2080);
FORCEPROP 1 LASTPIN (-3150 1900) $PN 2
J 0
(-3140 1880);
DISPLAY 0.489362 (-3140 1880);
FORCEPROP 1 LAST MATERIAL X6S
J 0
(-3100 1900);
DISPLAY 0.489362 (-3100 1900);
PAINT SKYBLUE (-3100 1900);
FORCEPROP 1 LAST TOLERANCE 20%
J 0
(-3100 1950);
DISPLAY 0.489362 (-3100 1950);
PAINT SKYBLUE (-3100 1950);
FORCEPROP 1 LAST VALUE 22UF
J 0
(-3100 2050);
DISPLAY 0.489362 (-3100 2050);
PAINT SKYBLUE (-3100 2050);
FORCEPROP 1 LAST PART_NUMBER CH622KMEB02
J 0
(-3100 1850);
DISPLAY 0.489362 (-3100 1850);
PAINT SKYBLUE (-3100 1850);
FORCEPROP 1 LAST VOLTAGE 4V
J 0
(-3100 2000);
DISPLAY 0.489362 (-3100 2000);
PAINT SKYBLUE (-3100 2000);
FORCEPROP 1 LAST PACK_TYPE C0402
J 0
(-3100 1800);
DISPLAY 0.489362 (-3100 1800);
PAINT SKYBLUE (-3100 1800);
FORCEPROP 2 LAST CDS_LIB pure_quanta
J 0
(-3150 2000);
PAINT MONO (-3150 2000);
DISPLAY INVISIBLE (-3150 2000);
FORCEPROP 1 LAST PATH I117
J 0
(-3100 2150);
DISPLAY 0.978723 (-3100 2150);
PAINT WHITE (-3100 2150);
DISPLAY INVISIBLE (-3100 2150);
FORCEADD Q_CAP..1
(-2700 1400);
FORCEPROP 1 LAST LOCATION C2630
J 0
(-2650 1500);
DISPLAY 0.489362 (-2650 1500);
PAINT SKYBLUE (-2650 1500);
FORCEPROP 2 LAST $SEC 1
J 0
(-2650 1600);
DISPLAY 0.680851 (-2650 1600);
PAINT MONO (-2650 1600);
DISPLAY INVISIBLE (-2650 1600);
FORCEPROP 2 LAST CDS_SEC 1
J 0
(-2650 1600);
DISPLAY 1.021277 (-2650 1600);
DISPLAY INVISIBLE (-2650 1600);
FORCEPROP 1 LASTPIN (-2700 1500) $PN 1
J 0
(-2690 1480);
DISPLAY 0.489362 (-2690 1480);
FORCEPROP 1 LASTPIN (-2700 1300) $PN 2
J 0
(-2690 1280);
DISPLAY 0.489362 (-2690 1280);
FORCEPROP 1 LAST MATERIAL X6S
J 0
(-2650 1300);
DISPLAY 0.489362 (-2650 1300);
PAINT SKYBLUE (-2650 1300);
FORCEPROP 1 LAST TOLERANCE 20%
J 0
(-2650 1350);
DISPLAY 0.489362 (-2650 1350);
PAINT SKYBLUE (-2650 1350);
FORCEPROP 1 LAST VALUE 22UF
J 0
(-2650 1450);
DISPLAY 0.489362 (-2650 1450);
PAINT SKYBLUE (-2650 1450);
FORCEPROP 1 LAST PART_NUMBER CH622KMEB02
J 0
(-2650 1250);
DISPLAY 0.489362 (-2650 1250);
PAINT SKYBLUE (-2650 1250);
FORCEPROP 1 LAST VOLTAGE 4V
J 0
(-2650 1400);
DISPLAY 0.489362 (-2650 1400);
PAINT SKYBLUE (-2650 1400);
FORCEPROP 1 LAST PACK_TYPE C0402
J 0
(-2650 1200);
DISPLAY 0.489362 (-2650 1200);
PAINT SKYBLUE (-2650 1200);
FORCEPROP 2 LAST CDS_LIB pure_quanta
J 0
(-2700 1400);
PAINT MONO (-2700 1400);
DISPLAY INVISIBLE (-2700 1400);
FORCEPROP 1 LAST PATH I118
J 0
(-2650 1550);
DISPLAY 0.978723 (-2650 1550);
PAINT WHITE (-2650 1550);
DISPLAY INVISIBLE (-2650 1550);
FORCEADD Q_CAP..1
(-2700 2000);
FORCEPROP 1 LAST LOCATION C2629
J 0
(-2650 2100);
DISPLAY 0.489362 (-2650 2100);
PAINT SKYBLUE (-2650 2100);
FORCEPROP 2 LAST $SEC 1
J 0
(-2650 2200);
DISPLAY 0.680851 (-2650 2200);
PAINT MONO (-2650 2200);
DISPLAY INVISIBLE (-2650 2200);
FORCEPROP 2 LAST CDS_SEC 1
J 0
(-2650 2200);
DISPLAY 1.021277 (-2650 2200);
DISPLAY INVISIBLE (-2650 2200);
FORCEPROP 1 LASTPIN (-2700 2100) $PN 1
J 0
(-2690 2080);
DISPLAY 0.489362 (-2690 2080);
FORCEPROP 1 LASTPIN (-2700 1900) $PN 2
J 0
(-2690 1880);
DISPLAY 0.489362 (-2690 1880);
FORCEPROP 1 LAST MATERIAL X6S
J 0
(-2650 1900);
DISPLAY 0.489362 (-2650 1900);
PAINT SKYBLUE (-2650 1900);
FORCEPROP 1 LAST TOLERANCE 20%
J 0
(-2650 1950);
DISPLAY 0.489362 (-2650 1950);
PAINT SKYBLUE (-2650 1950);
FORCEPROP 1 LAST VALUE 22UF
J 0
(-2650 2050);
DISPLAY 0.489362 (-2650 2050);
PAINT SKYBLUE (-2650 2050);
FORCEPROP 1 LAST PART_NUMBER CH622KMEB02
J 0
(-2650 1850);
DISPLAY 0.489362 (-2650 1850);
PAINT SKYBLUE (-2650 1850);
FORCEPROP 1 LAST VOLTAGE 4V
J 0
(-2650 2000);
DISPLAY 0.489362 (-2650 2000);
PAINT SKYBLUE (-2650 2000);
FORCEPROP 1 LAST PACK_TYPE C0402
J 0
(-2650 1800);
DISPLAY 0.489362 (-2650 1800);
PAINT SKYBLUE (-2650 1800);
FORCEPROP 2 LAST CDS_LIB pure_quanta
J 0
(-2700 2000);
PAINT MONO (-2700 2000);
DISPLAY INVISIBLE (-2700 2000);
FORCEPROP 1 LAST PATH I119
J 0
(-2650 2150);
DISPLAY 0.978723 (-2650 2150);
PAINT WHITE (-2650 2150);
DISPLAY INVISIBLE (-2650 2150);
FORCEADD UNIVERSAL_POWER..1
(-9075 3275);
FORCEPROP 3 LASTPIN (-9075 3225) SIG_NAME PVDDCR_SOC_P0\g
J 0
(-9065 3235);
DISPLAY 0.659574 (-9065 3235);
PAINT MONO (-9065 3235);
DISPLAY INVISIBLE (-9065 3235);
FORCEPROP 1 LAST HDL_POWER PVDDCR_SOC_P0
J 1
(-9075 3325);
DISPLAY 0.489362 (-9075 3325);
PAINT GREEN (-9075 3325);
FORCEPROP 2 LAST CDS_LIB pure_quanta_power
J 0
(-9075 3275);
DISPLAY INVISIBLE (-9075 3275);
FORCEPROP 1 LAST PATH I12
J 0
(-9025 3300);
DISPLAY 0.872340 (-9025 3300);
PAINT AQUA (-9025 3300);
DISPLAY INVISIBLE (-9025 3300);
FORCEADD Q_CAP..1
(-2250 1400);
FORCEPROP 1 LAST LOCATION C2636
J 0
(-2200 1500);
DISPLAY 0.489362 (-2200 1500);
PAINT SKYBLUE (-2200 1500);
FORCEPROP 2 LAST $SEC 1
J 0
(-2200 1600);
DISPLAY 0.680851 (-2200 1600);
PAINT MONO (-2200 1600);
DISPLAY INVISIBLE (-2200 1600);
FORCEPROP 2 LAST CDS_SEC 1
J 0
(-2200 1600);
DISPLAY 1.021277 (-2200 1600);
DISPLAY INVISIBLE (-2200 1600);
FORCEPROP 1 LASTPIN (-2250 1500) $PN 1
J 0
(-2240 1480);
DISPLAY 0.489362 (-2240 1480);
FORCEPROP 1 LASTPIN (-2250 1300) $PN 2
J 0
(-2240 1280);
DISPLAY 0.489362 (-2240 1280);
FORCEPROP 1 LAST MATERIAL X6S
J 0
(-2200 1300);
DISPLAY 0.489362 (-2200 1300);
PAINT SKYBLUE (-2200 1300);
FORCEPROP 1 LAST TOLERANCE 20%
J 0
(-2200 1350);
DISPLAY 0.489362 (-2200 1350);
PAINT SKYBLUE (-2200 1350);
FORCEPROP 1 LAST VALUE 22UF
J 0
(-2200 1450);
DISPLAY 0.489362 (-2200 1450);
PAINT SKYBLUE (-2200 1450);
FORCEPROP 1 LAST PART_NUMBER CH622KMEB02
J 0
(-2200 1250);
DISPLAY 0.489362 (-2200 1250);
PAINT SKYBLUE (-2200 1250);
FORCEPROP 1 LAST VOLTAGE 4V
J 0
(-2200 1400);
DISPLAY 0.489362 (-2200 1400);
PAINT SKYBLUE (-2200 1400);
FORCEPROP 1 LAST PACK_TYPE C0402
J 0
(-2200 1200);
DISPLAY 0.489362 (-2200 1200);
PAINT SKYBLUE (-2200 1200);
FORCEPROP 2 LAST CDS_LIB pure_quanta
J 0
(-2250 1400);
PAINT MONO (-2250 1400);
DISPLAY INVISIBLE (-2250 1400);
FORCEPROP 1 LAST PATH I120
J 0
(-2200 1550);
DISPLAY 0.978723 (-2200 1550);
PAINT WHITE (-2200 1550);
DISPLAY INVISIBLE (-2200 1550);
FORCEADD Q_CAP..1
(-2250 2000);
FORCEPROP 1 LAST LOCATION C2635
J 0
(-2200 2100);
DISPLAY 0.489362 (-2200 2100);
PAINT SKYBLUE (-2200 2100);
FORCEPROP 2 LAST $SEC 1
J 0
(-2200 2200);
DISPLAY 0.680851 (-2200 2200);
PAINT MONO (-2200 2200);
DISPLAY INVISIBLE (-2200 2200);
FORCEPROP 2 LAST CDS_SEC 1
J 0
(-2200 2200);
DISPLAY 1.021277 (-2200 2200);
DISPLAY INVISIBLE (-2200 2200);
FORCEPROP 1 LASTPIN (-2250 2100) $PN 1
J 0
(-2240 2080);
DISPLAY 0.489362 (-2240 2080);
FORCEPROP 1 LASTPIN (-2250 1900) $PN 2
J 0
(-2240 1880);
DISPLAY 0.489362 (-2240 1880);
FORCEPROP 1 LAST MATERIAL X6S
J 0
(-2200 1900);
DISPLAY 0.489362 (-2200 1900);
PAINT SKYBLUE (-2200 1900);
FORCEPROP 1 LAST TOLERANCE 20%
J 0
(-2200 1950);
DISPLAY 0.489362 (-2200 1950);
PAINT SKYBLUE (-2200 1950);
FORCEPROP 1 LAST VALUE 22UF
J 0
(-2200 2050);
DISPLAY 0.489362 (-2200 2050);
PAINT SKYBLUE (-2200 2050);
FORCEPROP 1 LAST PART_NUMBER CH622KMEB02
J 0
(-2200 1850);
DISPLAY 0.489362 (-2200 1850);
PAINT SKYBLUE (-2200 1850);
FORCEPROP 1 LAST VOLTAGE 4V
J 0
(-2200 2000);
DISPLAY 0.489362 (-2200 2000);
PAINT SKYBLUE (-2200 2000);
FORCEPROP 1 LAST PACK_TYPE C0402
J 0
(-2200 1800);
DISPLAY 0.489362 (-2200 1800);
PAINT SKYBLUE (-2200 1800);
FORCEPROP 2 LAST CDS_LIB pure_quanta
J 0
(-2250 2000);
PAINT MONO (-2250 2000);
DISPLAY INVISIBLE (-2250 2000);
FORCEPROP 1 LAST PATH I121
J 0
(-2200 2150);
DISPLAY 0.978723 (-2200 2150);
PAINT WHITE (-2200 2150);
DISPLAY INVISIBLE (-2200 2150);
FORCEADD Q_CAP..1
(-4050 2625);
FORCEPROP 1 LAST LOCATION C2608
J 0
(-4000 2725);
DISPLAY 0.489362 (-4000 2725);
PAINT SKYBLUE (-4000 2725);
FORCEPROP 2 LAST $SEC 1
J 0
(-4000 2825);
DISPLAY 0.680851 (-4000 2825);
PAINT MONO (-4000 2825);
DISPLAY INVISIBLE (-4000 2825);
FORCEPROP 2 LAST CDS_SEC 1
J 0
(-4000 2825);
DISPLAY 1.021277 (-4000 2825);
DISPLAY INVISIBLE (-4000 2825);
FORCEPROP 1 LASTPIN (-4050 2725) $PN 1
J 0
(-4040 2705);
DISPLAY 0.489362 (-4040 2705);
FORCEPROP 1 LASTPIN (-4050 2525) $PN 2
J 0
(-4040 2505);
DISPLAY 0.489362 (-4040 2505);
FORCEPROP 1 LAST MATERIAL X6S
J 0
(-4000 2525);
DISPLAY 0.489362 (-4000 2525);
PAINT SKYBLUE (-4000 2525);
FORCEPROP 1 LAST TOLERANCE 20%
J 0
(-4000 2575);
DISPLAY 0.489362 (-4000 2575);
PAINT SKYBLUE (-4000 2575);
FORCEPROP 1 LAST VALUE 22UF
J 0
(-4000 2675);
DISPLAY 0.489362 (-4000 2675);
PAINT SKYBLUE (-4000 2675);
FORCEPROP 1 LAST PART_NUMBER CH622KMEB02
J 0
(-4000 2475);
DISPLAY 0.489362 (-4000 2475);
PAINT SKYBLUE (-4000 2475);
FORCEPROP 1 LAST VOLTAGE 4V
J 0
(-4000 2625);
DISPLAY 0.489362 (-4000 2625);
PAINT SKYBLUE (-4000 2625);
FORCEPROP 1 LAST PACK_TYPE C0402
J 0
(-4000 2425);
DISPLAY 0.489362 (-4000 2425);
PAINT SKYBLUE (-4000 2425);
FORCEPROP 2 LAST CDS_LIB pure_quanta
J 0
(-4050 2625);
PAINT MONO (-4050 2625);
DISPLAY INVISIBLE (-4050 2625);
FORCEPROP 1 LAST PATH I122
J 0
(-4000 2775);
DISPLAY 0.978723 (-4000 2775);
PAINT WHITE (-4000 2775);
DISPLAY INVISIBLE (-4000 2775);
FORCEADD Q_CAP..1
(-3600 2625);
FORCEPROP 1 LAST LOCATION C2615
J 0
(-3550 2725);
DISPLAY 0.489362 (-3550 2725);
PAINT SKYBLUE (-3550 2725);
FORCEPROP 2 LAST $SEC 1
J 0
(-3550 2825);
DISPLAY 0.680851 (-3550 2825);
PAINT MONO (-3550 2825);
DISPLAY INVISIBLE (-3550 2825);
FORCEPROP 2 LAST CDS_SEC 1
J 0
(-3550 2825);
DISPLAY 1.021277 (-3550 2825);
DISPLAY INVISIBLE (-3550 2825);
FORCEPROP 1 LASTPIN (-3600 2725) $PN 1
J 0
(-3590 2705);
DISPLAY 0.489362 (-3590 2705);
FORCEPROP 1 LASTPIN (-3600 2525) $PN 2
J 0
(-3590 2505);
DISPLAY 0.489362 (-3590 2505);
FORCEPROP 1 LAST MATERIAL X6S
J 0
(-3550 2525);
DISPLAY 0.489362 (-3550 2525);
PAINT SKYBLUE (-3550 2525);
FORCEPROP 1 LAST TOLERANCE 20%
J 0
(-3550 2575);
DISPLAY 0.489362 (-3550 2575);
PAINT SKYBLUE (-3550 2575);
FORCEPROP 1 LAST VALUE 22UF
J 0
(-3550 2675);
DISPLAY 0.489362 (-3550 2675);
PAINT SKYBLUE (-3550 2675);
FORCEPROP 1 LAST PART_NUMBER CH622KMEB02
J 0
(-3550 2475);
DISPLAY 0.489362 (-3550 2475);
PAINT SKYBLUE (-3550 2475);
FORCEPROP 1 LAST VOLTAGE 4V
J 0
(-3550 2625);
DISPLAY 0.489362 (-3550 2625);
PAINT SKYBLUE (-3550 2625);
FORCEPROP 1 LAST PACK_TYPE C0402
J 0
(-3550 2425);
DISPLAY 0.489362 (-3550 2425);
PAINT SKYBLUE (-3550 2425);
FORCEPROP 2 LAST CDS_LIB pure_quanta
J 0
(-3600 2625);
PAINT MONO (-3600 2625);
DISPLAY INVISIBLE (-3600 2625);
FORCEPROP 1 LAST PATH I123
J 0
(-3550 2775);
DISPLAY 0.978723 (-3550 2775);
PAINT WHITE (-3550 2775);
DISPLAY INVISIBLE (-3550 2775);
FORCEADD Q_CAP..1
(-4050 3275);
FORCEPROP 1 LAST LOCATION C2607
J 0
(-4000 3375);
DISPLAY 0.489362 (-4000 3375);
PAINT SKYBLUE (-4000 3375);
FORCEPROP 2 LAST $SEC 1
J 0
(-4000 3475);
DISPLAY 0.680851 (-4000 3475);
PAINT MONO (-4000 3475);
DISPLAY INVISIBLE (-4000 3475);
FORCEPROP 2 LAST CDS_SEC 1
J 0
(-4000 3475);
DISPLAY 1.021277 (-4000 3475);
DISPLAY INVISIBLE (-4000 3475);
FORCEPROP 1 LASTPIN (-4050 3375) $PN 1
J 0
(-4040 3355);
DISPLAY 0.489362 (-4040 3355);
FORCEPROP 1 LASTPIN (-4050 3175) $PN 2
J 0
(-4040 3155);
DISPLAY 0.489362 (-4040 3155);
FORCEPROP 1 LAST MATERIAL X6S
J 0
(-4000 3175);
DISPLAY 0.489362 (-4000 3175);
PAINT SKYBLUE (-4000 3175);
FORCEPROP 1 LAST TOLERANCE 20%
J 0
(-4000 3225);
DISPLAY 0.489362 (-4000 3225);
PAINT SKYBLUE (-4000 3225);
FORCEPROP 1 LAST VALUE 22UF
J 0
(-4000 3325);
DISPLAY 0.489362 (-4000 3325);
PAINT SKYBLUE (-4000 3325);
FORCEPROP 1 LAST PART_NUMBER CH622KMEB02
J 0
(-4000 3125);
DISPLAY 0.489362 (-4000 3125);
PAINT SKYBLUE (-4000 3125);
FORCEPROP 1 LAST VOLTAGE 4V
J 0
(-4000 3275);
DISPLAY 0.489362 (-4000 3275);
PAINT SKYBLUE (-4000 3275);
FORCEPROP 1 LAST PACK_TYPE C0402
J 0
(-4000 3075);
DISPLAY 0.489362 (-4000 3075);
PAINT SKYBLUE (-4000 3075);
FORCEPROP 2 LAST CDS_LIB pure_quanta
J 0
(-4050 3275);
PAINT MONO (-4050 3275);
DISPLAY INVISIBLE (-4050 3275);
FORCEPROP 1 LAST PATH I124
J 0
(-4000 3425);
DISPLAY 0.978723 (-4000 3425);
PAINT WHITE (-4000 3425);
DISPLAY INVISIBLE (-4000 3425);
FORCEADD Q_CAP..1
(-3600 3275);
FORCEPROP 1 LAST LOCATION C2614
J 0
(-3550 3375);
DISPLAY 0.489362 (-3550 3375);
PAINT SKYBLUE (-3550 3375);
FORCEPROP 2 LAST $SEC 1
J 0
(-3550 3475);
DISPLAY 0.680851 (-3550 3475);
PAINT MONO (-3550 3475);
DISPLAY INVISIBLE (-3550 3475);
FORCEPROP 2 LAST CDS_SEC 1
J 0
(-3550 3475);
DISPLAY 1.021277 (-3550 3475);
DISPLAY INVISIBLE (-3550 3475);
FORCEPROP 1 LASTPIN (-3600 3375) $PN 1
J 0
(-3590 3355);
DISPLAY 0.489362 (-3590 3355);
FORCEPROP 1 LASTPIN (-3600 3175) $PN 2
J 0
(-3590 3155);
DISPLAY 0.489362 (-3590 3155);
FORCEPROP 1 LAST MATERIAL X6S
J 0
(-3550 3175);
DISPLAY 0.489362 (-3550 3175);
PAINT SKYBLUE (-3550 3175);
FORCEPROP 1 LAST TOLERANCE 20%
J 0
(-3550 3225);
DISPLAY 0.489362 (-3550 3225);
PAINT SKYBLUE (-3550 3225);
FORCEPROP 1 LAST VALUE 22UF
J 0
(-3550 3325);
DISPLAY 0.489362 (-3550 3325);
PAINT SKYBLUE (-3550 3325);
FORCEPROP 1 LAST PART_NUMBER CH622KMEB02
J 0
(-3550 3125);
DISPLAY 0.489362 (-3550 3125);
PAINT SKYBLUE (-3550 3125);
FORCEPROP 1 LAST VOLTAGE 4V
J 0
(-3550 3275);
DISPLAY 0.489362 (-3550 3275);
PAINT SKYBLUE (-3550 3275);
FORCEPROP 1 LAST PACK_TYPE C0402
J 0
(-3550 3075);
DISPLAY 0.489362 (-3550 3075);
PAINT SKYBLUE (-3550 3075);
FORCEPROP 2 LAST CDS_LIB pure_quanta
J 0
(-3600 3275);
PAINT MONO (-3600 3275);
DISPLAY INVISIBLE (-3600 3275);
FORCEPROP 1 LAST PATH I125
J 0
(-3550 3425);
DISPLAY 0.978723 (-3550 3425);
PAINT WHITE (-3550 3425);
DISPLAY INVISIBLE (-3550 3425);
FORCEADD Q_CAP..1
(-3150 2625);
FORCEPROP 1 LAST LOCATION C2622
J 0
(-3100 2725);
DISPLAY 0.489362 (-3100 2725);
PAINT SKYBLUE (-3100 2725);
FORCEPROP 2 LAST $SEC 1
J 0
(-3100 2825);
DISPLAY 0.680851 (-3100 2825);
PAINT MONO (-3100 2825);
DISPLAY INVISIBLE (-3100 2825);
FORCEPROP 2 LAST CDS_SEC 1
J 0
(-3100 2825);
DISPLAY 1.021277 (-3100 2825);
DISPLAY INVISIBLE (-3100 2825);
FORCEPROP 1 LASTPIN (-3150 2725) $PN 1
J 0
(-3140 2705);
DISPLAY 0.489362 (-3140 2705);
FORCEPROP 1 LASTPIN (-3150 2525) $PN 2
J 0
(-3140 2505);
DISPLAY 0.489362 (-3140 2505);
FORCEPROP 1 LAST MATERIAL X6S
J 0
(-3100 2525);
DISPLAY 0.489362 (-3100 2525);
PAINT SKYBLUE (-3100 2525);
FORCEPROP 1 LAST TOLERANCE 20%
J 0
(-3100 2575);
DISPLAY 0.489362 (-3100 2575);
PAINT SKYBLUE (-3100 2575);
FORCEPROP 1 LAST VALUE 22UF
J 0
(-3100 2675);
DISPLAY 0.489362 (-3100 2675);
PAINT SKYBLUE (-3100 2675);
FORCEPROP 1 LAST PART_NUMBER CH622KMEB02
J 0
(-3100 2475);
DISPLAY 0.489362 (-3100 2475);
PAINT SKYBLUE (-3100 2475);
FORCEPROP 1 LAST VOLTAGE 4V
J 0
(-3100 2625);
DISPLAY 0.489362 (-3100 2625);
PAINT SKYBLUE (-3100 2625);
FORCEPROP 1 LAST PACK_TYPE C0402
J 0
(-3100 2425);
DISPLAY 0.489362 (-3100 2425);
PAINT SKYBLUE (-3100 2425);
FORCEPROP 2 LAST CDS_LIB pure_quanta
J 0
(-3150 2625);
PAINT MONO (-3150 2625);
DISPLAY INVISIBLE (-3150 2625);
FORCEPROP 1 LAST PATH I126
J 0
(-3100 2775);
DISPLAY 0.978723 (-3100 2775);
PAINT WHITE (-3100 2775);
DISPLAY INVISIBLE (-3100 2775);
FORCEADD Q_CAP..1
(-3150 3275);
FORCEPROP 1 LAST LOCATION C2621
J 0
(-3100 3375);
DISPLAY 0.489362 (-3100 3375);
PAINT SKYBLUE (-3100 3375);
FORCEPROP 2 LAST $SEC 1
J 0
(-3100 3475);
DISPLAY 0.680851 (-3100 3475);
PAINT MONO (-3100 3475);
DISPLAY INVISIBLE (-3100 3475);
FORCEPROP 2 LAST CDS_SEC 1
J 0
(-3100 3475);
DISPLAY 1.021277 (-3100 3475);
DISPLAY INVISIBLE (-3100 3475);
FORCEPROP 1 LASTPIN (-3150 3375) $PN 1
J 0
(-3140 3355);
DISPLAY 0.489362 (-3140 3355);
FORCEPROP 1 LASTPIN (-3150 3175) $PN 2
J 0
(-3140 3155);
DISPLAY 0.489362 (-3140 3155);
FORCEPROP 1 LAST MATERIAL X6S
J 0
(-3100 3175);
DISPLAY 0.489362 (-3100 3175);
PAINT SKYBLUE (-3100 3175);
FORCEPROP 1 LAST TOLERANCE 20%
J 0
(-3100 3225);
DISPLAY 0.489362 (-3100 3225);
PAINT SKYBLUE (-3100 3225);
FORCEPROP 1 LAST VALUE 22UF
J 0
(-3100 3325);
DISPLAY 0.489362 (-3100 3325);
PAINT SKYBLUE (-3100 3325);
FORCEPROP 1 LAST PART_NUMBER CH622KMEB02
J 0
(-3100 3125);
DISPLAY 0.489362 (-3100 3125);
PAINT SKYBLUE (-3100 3125);
FORCEPROP 1 LAST VOLTAGE 4V
J 0
(-3100 3275);
DISPLAY 0.489362 (-3100 3275);
PAINT SKYBLUE (-3100 3275);
FORCEPROP 1 LAST PACK_TYPE C0402
J 0
(-3100 3075);
DISPLAY 0.489362 (-3100 3075);
PAINT SKYBLUE (-3100 3075);
FORCEPROP 2 LAST CDS_LIB pure_quanta
J 0
(-3150 3275);
PAINT MONO (-3150 3275);
DISPLAY INVISIBLE (-3150 3275);
FORCEPROP 1 LAST PATH I127
J 0
(-3100 3425);
DISPLAY 0.978723 (-3100 3425);
PAINT WHITE (-3100 3425);
DISPLAY INVISIBLE (-3100 3425);
FORCEADD UNIVERSAL_GND..1
(-3150 3950);
FORCEPROP 3 LASTPIN (-3150 4000) SIG_NAME GND\g
J 0
(-3140 4010);
DISPLAY 0.659574 (-3140 4010);
PAINT MONO (-3140 4010);
DISPLAY INVISIBLE (-3140 4010);
FORCEPROP 2 LAST CDS_LIB pure_quanta_power
J 0
(-3150 3950);
DISPLAY INVISIBLE (-3150 3950);
FORCEPROP 1 LAST PATH I128
J 0
(-3075 3950);
DISPLAY 0.872340 (-3075 3950);
PAINT AQUA (-3075 3950);
DISPLAY INVISIBLE (-3075 3950);
FORCEPROP 1 LAST HDL_POWER GND
J 1
(-3125 3875);
DISPLAY 0.872340 (-3125 3875);
PAINT GREEN (-3125 3875);
DISPLAY INVISIBLE (-3125 3875);
FORCEADD Q_CAP..1
(-2700 2625);
FORCEPROP 1 LAST LOCATION C2628
J 0
(-2650 2725);
DISPLAY 0.489362 (-2650 2725);
PAINT SKYBLUE (-2650 2725);
FORCEPROP 2 LAST $SEC 1
J 0
(-2650 2825);
DISPLAY 0.680851 (-2650 2825);
PAINT MONO (-2650 2825);
DISPLAY INVISIBLE (-2650 2825);
FORCEPROP 2 LAST CDS_SEC 1
J 0
(-2650 2825);
DISPLAY 1.021277 (-2650 2825);
DISPLAY INVISIBLE (-2650 2825);
FORCEPROP 1 LASTPIN (-2700 2725) $PN 1
J 0
(-2690 2705);
DISPLAY 0.489362 (-2690 2705);
FORCEPROP 1 LASTPIN (-2700 2525) $PN 2
J 0
(-2690 2505);
DISPLAY 0.489362 (-2690 2505);
FORCEPROP 1 LAST MATERIAL X6S
J 0
(-2650 2525);
DISPLAY 0.489362 (-2650 2525);
PAINT SKYBLUE (-2650 2525);
FORCEPROP 1 LAST TOLERANCE 20%
J 0
(-2650 2575);
DISPLAY 0.489362 (-2650 2575);
PAINT SKYBLUE (-2650 2575);
FORCEPROP 1 LAST VALUE 22UF
J 0
(-2650 2675);
DISPLAY 0.489362 (-2650 2675);
PAINT SKYBLUE (-2650 2675);
FORCEPROP 1 LAST PART_NUMBER CH622KMEB02
J 0
(-2650 2475);
DISPLAY 0.489362 (-2650 2475);
PAINT SKYBLUE (-2650 2475);
FORCEPROP 1 LAST VOLTAGE 4V
J 0
(-2650 2625);
DISPLAY 0.489362 (-2650 2625);
PAINT SKYBLUE (-2650 2625);
FORCEPROP 1 LAST PACK_TYPE C0402
J 0
(-2650 2425);
DISPLAY 0.489362 (-2650 2425);
PAINT SKYBLUE (-2650 2425);
FORCEPROP 2 LAST CDS_LIB pure_quanta
J 0
(-2700 2625);
PAINT MONO (-2700 2625);
DISPLAY INVISIBLE (-2700 2625);
FORCEPROP 1 LAST PATH I129
J 0
(-2650 2775);
DISPLAY 0.978723 (-2650 2775);
PAINT WHITE (-2650 2775);
DISPLAY INVISIBLE (-2650 2775);
FORCEADD Q_CAP..1
(-9075 3725);
FORCEPROP 1 LAST LOCATION C2530
J 0
(-9025 3825);
DISPLAY 0.489362 (-9025 3825);
PAINT SKYBLUE (-9025 3825);
FORCEPROP 2 LAST $SEC 1
J 0
(-9025 3925);
DISPLAY 0.680851 (-9025 3925);
PAINT MONO (-9025 3925);
DISPLAY INVISIBLE (-9025 3925);
FORCEPROP 2 LAST CDS_SEC 1
J 0
(-9025 3925);
DISPLAY 1.021277 (-9025 3925);
DISPLAY INVISIBLE (-9025 3925);
FORCEPROP 1 LASTPIN (-9075 3825) $PN 1
J 0
(-9065 3805);
DISPLAY 0.489362 (-9065 3805);
FORCEPROP 1 LASTPIN (-9075 3625) $PN 2
J 0
(-9065 3605);
DISPLAY 0.489362 (-9065 3605);
FORCEPROP 1 LAST MATERIAL X6S
J 0
(-9025 3625);
DISPLAY 0.489362 (-9025 3625);
PAINT SKYBLUE (-9025 3625);
FORCEPROP 1 LAST TOLERANCE 20%
J 0
(-9025 3675);
DISPLAY 0.489362 (-9025 3675);
PAINT SKYBLUE (-9025 3675);
FORCEPROP 1 LAST VALUE 22UF
J 0
(-9025 3775);
DISPLAY 0.489362 (-9025 3775);
PAINT SKYBLUE (-9025 3775);
FORCEPROP 1 LAST PART_NUMBER CH622KMEB02
J 0
(-9025 3575);
DISPLAY 0.489362 (-9025 3575);
PAINT SKYBLUE (-9025 3575);
FORCEPROP 1 LAST VOLTAGE 4V
J 0
(-9025 3725);
DISPLAY 0.489362 (-9025 3725);
PAINT SKYBLUE (-9025 3725);
FORCEPROP 1 LAST PACK_TYPE C0402
J 0
(-9025 3525);
DISPLAY 0.489362 (-9025 3525);
PAINT SKYBLUE (-9025 3525);
FORCEPROP 2 LAST CDS_LIB pure_quanta
J 0
(-9075 3725);
PAINT MONO (-9075 3725);
DISPLAY INVISIBLE (-9075 3725);
FORCEPROP 1 LAST PATH I13
J 0
(-9025 3875);
DISPLAY 0.978723 (-9025 3875);
PAINT WHITE (-9025 3875);
DISPLAY INVISIBLE (-9025 3875);
FORCEADD Q_CAP..1
(-2250 2625);
FORCEPROP 1 LAST LOCATION C2634
J 0
(-2200 2725);
DISPLAY 0.489362 (-2200 2725);
PAINT SKYBLUE (-2200 2725);
FORCEPROP 2 LAST $SEC 1
J 0
(-2200 2825);
DISPLAY 0.680851 (-2200 2825);
PAINT MONO (-2200 2825);
DISPLAY INVISIBLE (-2200 2825);
FORCEPROP 2 LAST CDS_SEC 1
J 0
(-2200 2825);
DISPLAY 1.021277 (-2200 2825);
DISPLAY INVISIBLE (-2200 2825);
FORCEPROP 1 LASTPIN (-2250 2725) $PN 1
J 0
(-2240 2705);
DISPLAY 0.489362 (-2240 2705);
FORCEPROP 1 LASTPIN (-2250 2525) $PN 2
J 0
(-2240 2505);
DISPLAY 0.489362 (-2240 2505);
FORCEPROP 1 LAST MATERIAL X6S
J 0
(-2200 2525);
DISPLAY 0.489362 (-2200 2525);
PAINT SKYBLUE (-2200 2525);
FORCEPROP 1 LAST TOLERANCE 20%
J 0
(-2200 2575);
DISPLAY 0.489362 (-2200 2575);
PAINT SKYBLUE (-2200 2575);
FORCEPROP 1 LAST VALUE 22UF
J 0
(-2200 2675);
DISPLAY 0.489362 (-2200 2675);
PAINT SKYBLUE (-2200 2675);
FORCEPROP 1 LAST PART_NUMBER CH622KMEB02
J 0
(-2200 2475);
DISPLAY 0.489362 (-2200 2475);
PAINT SKYBLUE (-2200 2475);
FORCEPROP 1 LAST VOLTAGE 4V
J 0
(-2200 2625);
DISPLAY 0.489362 (-2200 2625);
PAINT SKYBLUE (-2200 2625);
FORCEPROP 1 LAST PACK_TYPE C0402
J 0
(-2200 2425);
DISPLAY 0.489362 (-2200 2425);
PAINT SKYBLUE (-2200 2425);
FORCEPROP 2 LAST CDS_LIB pure_quanta
J 0
(-2250 2625);
PAINT MONO (-2250 2625);
DISPLAY INVISIBLE (-2250 2625);
FORCEPROP 1 LAST PATH I130
J 0
(-2200 2775);
DISPLAY 0.978723 (-2200 2775);
PAINT WHITE (-2200 2775);
DISPLAY INVISIBLE (-2200 2775);
FORCEADD Q_CAP..1
(-2700 3275);
FORCEPROP 1 LAST LOCATION C2627
J 0
(-2650 3375);
DISPLAY 0.489362 (-2650 3375);
PAINT SKYBLUE (-2650 3375);
FORCEPROP 2 LAST $SEC 1
J 0
(-2650 3475);
DISPLAY 0.680851 (-2650 3475);
PAINT MONO (-2650 3475);
DISPLAY INVISIBLE (-2650 3475);
FORCEPROP 2 LAST CDS_SEC 1
J 0
(-2650 3475);
DISPLAY 1.021277 (-2650 3475);
DISPLAY INVISIBLE (-2650 3475);
FORCEPROP 1 LASTPIN (-2700 3375) $PN 1
J 0
(-2690 3355);
DISPLAY 0.489362 (-2690 3355);
FORCEPROP 1 LASTPIN (-2700 3175) $PN 2
J 0
(-2690 3155);
DISPLAY 0.489362 (-2690 3155);
FORCEPROP 1 LAST MATERIAL X6S
J 0
(-2650 3175);
DISPLAY 0.489362 (-2650 3175);
PAINT SKYBLUE (-2650 3175);
FORCEPROP 1 LAST TOLERANCE 20%
J 0
(-2650 3225);
DISPLAY 0.489362 (-2650 3225);
PAINT SKYBLUE (-2650 3225);
FORCEPROP 1 LAST VALUE 22UF
J 0
(-2650 3325);
DISPLAY 0.489362 (-2650 3325);
PAINT SKYBLUE (-2650 3325);
FORCEPROP 1 LAST PART_NUMBER CH622KMEB02
J 0
(-2650 3125);
DISPLAY 0.489362 (-2650 3125);
PAINT SKYBLUE (-2650 3125);
FORCEPROP 1 LAST VOLTAGE 4V
J 0
(-2650 3275);
DISPLAY 0.489362 (-2650 3275);
PAINT SKYBLUE (-2650 3275);
FORCEPROP 1 LAST PACK_TYPE C0402
J 0
(-2650 3075);
DISPLAY 0.489362 (-2650 3075);
PAINT SKYBLUE (-2650 3075);
FORCEPROP 2 LAST CDS_LIB pure_quanta
J 0
(-2700 3275);
PAINT MONO (-2700 3275);
DISPLAY INVISIBLE (-2700 3275);
FORCEPROP 1 LAST PATH I131
J 0
(-2650 3425);
DISPLAY 0.978723 (-2650 3425);
PAINT WHITE (-2650 3425);
DISPLAY INVISIBLE (-2650 3425);
FORCEADD Q_CAP..1
(-2250 3275);
FORCEPROP 1 LAST LOCATION C2633
J 0
(-2200 3375);
DISPLAY 0.489362 (-2200 3375);
PAINT SKYBLUE (-2200 3375);
FORCEPROP 2 LAST $SEC 1
J 0
(-2200 3475);
DISPLAY 0.680851 (-2200 3475);
PAINT MONO (-2200 3475);
DISPLAY INVISIBLE (-2200 3475);
FORCEPROP 2 LAST CDS_SEC 1
J 0
(-2200 3475);
DISPLAY 1.021277 (-2200 3475);
DISPLAY INVISIBLE (-2200 3475);
FORCEPROP 1 LASTPIN (-2250 3375) $PN 1
J 0
(-2240 3355);
DISPLAY 0.489362 (-2240 3355);
FORCEPROP 1 LASTPIN (-2250 3175) $PN 2
J 0
(-2240 3155);
DISPLAY 0.489362 (-2240 3155);
FORCEPROP 1 LAST MATERIAL X6S
J 0
(-2200 3175);
DISPLAY 0.489362 (-2200 3175);
PAINT SKYBLUE (-2200 3175);
FORCEPROP 1 LAST TOLERANCE 20%
J 0
(-2200 3225);
DISPLAY 0.489362 (-2200 3225);
PAINT SKYBLUE (-2200 3225);
FORCEPROP 1 LAST VALUE 22UF
J 0
(-2200 3325);
DISPLAY 0.489362 (-2200 3325);
PAINT SKYBLUE (-2200 3325);
FORCEPROP 1 LAST PART_NUMBER CH622KMEB02
J 0
(-2200 3125);
DISPLAY 0.489362 (-2200 3125);
PAINT SKYBLUE (-2200 3125);
FORCEPROP 1 LAST VOLTAGE 4V
J 0
(-2200 3275);
DISPLAY 0.489362 (-2200 3275);
PAINT SKYBLUE (-2200 3275);
FORCEPROP 1 LAST PACK_TYPE C0402
J 0
(-2200 3075);
DISPLAY 0.489362 (-2200 3075);
PAINT SKYBLUE (-2200 3075);
FORCEPROP 2 LAST CDS_LIB pure_quanta
J 0
(-2250 3275);
PAINT MONO (-2250 3275);
DISPLAY INVISIBLE (-2250 3275);
FORCEPROP 1 LAST PATH I132
J 0
(-2200 3425);
DISPLAY 0.978723 (-2200 3425);
PAINT WHITE (-2200 3425);
DISPLAY INVISIBLE (-2200 3425);
FORCEADD Q_CAP..1
(-1800 1400);
FORCEPROP 1 LAST LOCATION C2642
J 0
(-1750 1500);
DISPLAY 0.489362 (-1750 1500);
PAINT SKYBLUE (-1750 1500);
FORCEPROP 2 LAST $SEC 1
J 0
(-1750 1600);
DISPLAY 0.680851 (-1750 1600);
PAINT MONO (-1750 1600);
DISPLAY INVISIBLE (-1750 1600);
FORCEPROP 2 LAST CDS_SEC 1
J 0
(-1750 1600);
DISPLAY 1.021277 (-1750 1600);
DISPLAY INVISIBLE (-1750 1600);
FORCEPROP 1 LASTPIN (-1800 1500) $PN 1
J 0
(-1790 1480);
DISPLAY 0.489362 (-1790 1480);
FORCEPROP 1 LASTPIN (-1800 1300) $PN 2
J 0
(-1790 1280);
DISPLAY 0.489362 (-1790 1280);
FORCEPROP 1 LAST MATERIAL X6S
J 0
(-1750 1300);
DISPLAY 0.489362 (-1750 1300);
PAINT SKYBLUE (-1750 1300);
FORCEPROP 1 LAST TOLERANCE 20%
J 0
(-1750 1350);
DISPLAY 0.489362 (-1750 1350);
PAINT SKYBLUE (-1750 1350);
FORCEPROP 1 LAST VALUE 22UF
J 0
(-1750 1450);
DISPLAY 0.489362 (-1750 1450);
PAINT SKYBLUE (-1750 1450);
FORCEPROP 1 LAST PART_NUMBER CH622KMEB02
J 0
(-1750 1250);
DISPLAY 0.489362 (-1750 1250);
PAINT SKYBLUE (-1750 1250);
FORCEPROP 1 LAST VOLTAGE 4V
J 0
(-1750 1400);
DISPLAY 0.489362 (-1750 1400);
PAINT SKYBLUE (-1750 1400);
FORCEPROP 1 LAST PACK_TYPE C0402
J 0
(-1750 1200);
DISPLAY 0.489362 (-1750 1200);
PAINT SKYBLUE (-1750 1200);
FORCEPROP 2 LAST CDS_LIB pure_quanta
J 0
(-1800 1400);
PAINT MONO (-1800 1400);
DISPLAY INVISIBLE (-1800 1400);
FORCEPROP 1 LAST PATH I133
J 0
(-1750 1550);
DISPLAY 0.978723 (-1750 1550);
PAINT WHITE (-1750 1550);
DISPLAY INVISIBLE (-1750 1550);
FORCEADD Q_CAP..1
(-1800 2000);
FORCEPROP 1 LAST LOCATION C2641
J 0
(-1750 2100);
DISPLAY 0.489362 (-1750 2100);
PAINT SKYBLUE (-1750 2100);
FORCEPROP 2 LAST $SEC 1
J 0
(-1750 2200);
DISPLAY 0.680851 (-1750 2200);
PAINT MONO (-1750 2200);
DISPLAY INVISIBLE (-1750 2200);
FORCEPROP 2 LAST CDS_SEC 1
J 0
(-1750 2200);
DISPLAY 1.021277 (-1750 2200);
DISPLAY INVISIBLE (-1750 2200);
FORCEPROP 1 LASTPIN (-1800 2100) $PN 1
J 0
(-1790 2080);
DISPLAY 0.489362 (-1790 2080);
FORCEPROP 1 LASTPIN (-1800 1900) $PN 2
J 0
(-1790 1880);
DISPLAY 0.489362 (-1790 1880);
FORCEPROP 1 LAST MATERIAL X6S
J 0
(-1750 1900);
DISPLAY 0.489362 (-1750 1900);
PAINT SKYBLUE (-1750 1900);
FORCEPROP 1 LAST TOLERANCE 20%
J 0
(-1750 1950);
DISPLAY 0.489362 (-1750 1950);
PAINT SKYBLUE (-1750 1950);
FORCEPROP 1 LAST VALUE 22UF
J 0
(-1750 2050);
DISPLAY 0.489362 (-1750 2050);
PAINT SKYBLUE (-1750 2050);
FORCEPROP 1 LAST PART_NUMBER CH622KMEB02
J 0
(-1750 1850);
DISPLAY 0.489362 (-1750 1850);
PAINT SKYBLUE (-1750 1850);
FORCEPROP 1 LAST VOLTAGE 4V
J 0
(-1750 2000);
DISPLAY 0.489362 (-1750 2000);
PAINT SKYBLUE (-1750 2000);
FORCEPROP 1 LAST PACK_TYPE C0402
J 0
(-1750 1800);
DISPLAY 0.489362 (-1750 1800);
PAINT SKYBLUE (-1750 1800);
FORCEPROP 2 LAST CDS_LIB pure_quanta
J 0
(-1800 2000);
PAINT MONO (-1800 2000);
DISPLAY INVISIBLE (-1800 2000);
FORCEPROP 1 LAST PATH I134
J 0
(-1750 2150);
DISPLAY 0.978723 (-1750 2150);
PAINT WHITE (-1750 2150);
DISPLAY INVISIBLE (-1750 2150);
FORCEADD Q_CAP..1
(-1350 1400);
FORCEPROP 1 LAST LOCATION C2648
J 0
(-1300 1500);
DISPLAY 0.489362 (-1300 1500);
PAINT SKYBLUE (-1300 1500);
FORCEPROP 2 LAST $SEC 1
J 0
(-1300 1600);
DISPLAY 0.680851 (-1300 1600);
PAINT MONO (-1300 1600);
DISPLAY INVISIBLE (-1300 1600);
FORCEPROP 2 LAST CDS_SEC 1
J 0
(-1300 1600);
DISPLAY 1.021277 (-1300 1600);
DISPLAY INVISIBLE (-1300 1600);
FORCEPROP 1 LASTPIN (-1350 1500) $PN 1
J 0
(-1340 1480);
DISPLAY 0.489362 (-1340 1480);
FORCEPROP 1 LASTPIN (-1350 1300) $PN 2
J 0
(-1340 1280);
DISPLAY 0.489362 (-1340 1280);
FORCEPROP 1 LAST MATERIAL X6S
J 0
(-1300 1300);
DISPLAY 0.489362 (-1300 1300);
PAINT SKYBLUE (-1300 1300);
FORCEPROP 1 LAST TOLERANCE 20%
J 0
(-1300 1350);
DISPLAY 0.489362 (-1300 1350);
PAINT SKYBLUE (-1300 1350);
FORCEPROP 1 LAST VALUE 22UF
J 0
(-1300 1450);
DISPLAY 0.489362 (-1300 1450);
PAINT SKYBLUE (-1300 1450);
FORCEPROP 1 LAST PART_NUMBER CH622KMEB02
J 0
(-1300 1250);
DISPLAY 0.489362 (-1300 1250);
PAINT SKYBLUE (-1300 1250);
FORCEPROP 1 LAST VOLTAGE 4V
J 0
(-1300 1400);
DISPLAY 0.489362 (-1300 1400);
PAINT SKYBLUE (-1300 1400);
FORCEPROP 1 LAST PACK_TYPE C0402
J 0
(-1300 1200);
DISPLAY 0.489362 (-1300 1200);
PAINT SKYBLUE (-1300 1200);
FORCEPROP 2 LAST CDS_LIB pure_quanta
J 0
(-1350 1400);
PAINT MONO (-1350 1400);
DISPLAY INVISIBLE (-1350 1400);
FORCEPROP 1 LAST PATH I135
J 0
(-1300 1550);
DISPLAY 0.978723 (-1300 1550);
PAINT WHITE (-1300 1550);
DISPLAY INVISIBLE (-1300 1550);
FORCEADD Q_CAP..1
(-1350 2000);
FORCEPROP 1 LAST LOCATION C2647
J 0
(-1300 2100);
DISPLAY 0.489362 (-1300 2100);
PAINT SKYBLUE (-1300 2100);
FORCEPROP 2 LAST $SEC 1
J 0
(-1300 2200);
DISPLAY 0.680851 (-1300 2200);
PAINT MONO (-1300 2200);
DISPLAY INVISIBLE (-1300 2200);
FORCEPROP 2 LAST CDS_SEC 1
J 0
(-1300 2200);
DISPLAY 1.021277 (-1300 2200);
DISPLAY INVISIBLE (-1300 2200);
FORCEPROP 1 LASTPIN (-1350 2100) $PN 1
J 0
(-1340 2080);
DISPLAY 0.489362 (-1340 2080);
FORCEPROP 1 LASTPIN (-1350 1900) $PN 2
J 0
(-1340 1880);
DISPLAY 0.489362 (-1340 1880);
FORCEPROP 1 LAST MATERIAL X6S
J 0
(-1300 1900);
DISPLAY 0.489362 (-1300 1900);
PAINT SKYBLUE (-1300 1900);
FORCEPROP 1 LAST TOLERANCE 20%
J 0
(-1300 1950);
DISPLAY 0.489362 (-1300 1950);
PAINT SKYBLUE (-1300 1950);
FORCEPROP 1 LAST VALUE 22UF
J 0
(-1300 2050);
DISPLAY 0.489362 (-1300 2050);
PAINT SKYBLUE (-1300 2050);
FORCEPROP 1 LAST PART_NUMBER CH622KMEB02
J 0
(-1300 1850);
DISPLAY 0.489362 (-1300 1850);
PAINT SKYBLUE (-1300 1850);
FORCEPROP 1 LAST VOLTAGE 4V
J 0
(-1300 2000);
DISPLAY 0.489362 (-1300 2000);
PAINT SKYBLUE (-1300 2000);
FORCEPROP 1 LAST PACK_TYPE C0402
J 0
(-1300 1800);
DISPLAY 0.489362 (-1300 1800);
PAINT SKYBLUE (-1300 1800);
FORCEPROP 2 LAST CDS_LIB pure_quanta
J 0
(-1350 2000);
PAINT MONO (-1350 2000);
DISPLAY INVISIBLE (-1350 2000);
FORCEPROP 1 LAST PATH I136
J 0
(-1300 2150);
DISPLAY 0.978723 (-1300 2150);
PAINT WHITE (-1300 2150);
DISPLAY INVISIBLE (-1300 2150);
FORCEADD UNIVERSAL_GND..1
(-500 1025);
FORCEPROP 3 LASTPIN (-500 1075) SIG_NAME GND\g
J 0
(-490 1085);
DISPLAY 0.659574 (-490 1085);
PAINT MONO (-490 1085);
DISPLAY INVISIBLE (-490 1085);
FORCEPROP 2 LAST CDS_LIB pure_quanta_power
J 0
(-500 1025);
PAINT MONO (-500 1025);
DISPLAY INVISIBLE (-500 1025);
FORCEPROP 1 LAST PATH I137
J 0
(-425 1025);
DISPLAY 0.872340 (-425 1025);
PAINT AQUA (-425 1025);
DISPLAY INVISIBLE (-425 1025);
FORCEPROP 1 LAST HDL_POWER GND
J 1
(-475 950);
DISPLAY 0.872340 (-475 950);
PAINT GREEN (-475 950);
DISPLAY INVISIBLE (-475 950);
FORCEADD Q_CAP..1
(-900 1400);
FORCEPROP 1 LAST LOCATION C3934
J 0
(-850 1500);
DISPLAY 0.489362 (-850 1500);
PAINT SKYBLUE (-850 1500);
FORCEPROP 2 LAST $SEC 1
J 0
(-850 1600);
DISPLAY 0.680851 (-850 1600);
PAINT MONO (-850 1600);
DISPLAY INVISIBLE (-850 1600);
FORCEPROP 2 LAST CDS_SEC 1
J 0
(-850 1600);
DISPLAY 1.021277 (-850 1600);
DISPLAY INVISIBLE (-850 1600);
FORCEPROP 1 LASTPIN (-900 1500) $PN 1
J 0
(-890 1480);
DISPLAY 0.489362 (-890 1480);
FORCEPROP 1 LASTPIN (-900 1300) $PN 2
J 0
(-890 1280);
DISPLAY 0.489362 (-890 1280);
FORCEPROP 1 LAST MATERIAL X6S
J 0
(-850 1300);
DISPLAY 0.489362 (-850 1300);
PAINT SKYBLUE (-850 1300);
FORCEPROP 1 LAST TOLERANCE 20%
J 0
(-850 1350);
DISPLAY 0.489362 (-850 1350);
PAINT SKYBLUE (-850 1350);
FORCEPROP 1 LAST VALUE 22UF
J 0
(-850 1450);
DISPLAY 0.489362 (-850 1450);
PAINT SKYBLUE (-850 1450);
FORCEPROP 1 LAST PART_NUMBER CH622KMEB02
J 0
(-850 1250);
DISPLAY 0.489362 (-850 1250);
PAINT SKYBLUE (-850 1250);
FORCEPROP 1 LAST VOLTAGE 4V
J 0
(-850 1400);
DISPLAY 0.489362 (-850 1400);
PAINT SKYBLUE (-850 1400);
FORCEPROP 1 LAST PACK_TYPE C0402
J 0
(-850 1200);
DISPLAY 0.489362 (-850 1200);
PAINT SKYBLUE (-850 1200);
FORCEPROP 2 LAST CDS_LIB pure_quanta
J 0
(-900 1400);
PAINT MONO (-900 1400);
DISPLAY INVISIBLE (-900 1400);
FORCEPROP 1 LAST PATH I138
J 0
(-850 1550);
DISPLAY 0.978723 (-850 1550);
PAINT WHITE (-850 1550);
DISPLAY INVISIBLE (-850 1550);
FORCEADD Q_CAP..1
(-900 2000);
FORCEPROP 1 LAST LOCATION C2653
J 0
(-850 2100);
DISPLAY 0.489362 (-850 2100);
PAINT SKYBLUE (-850 2100);
FORCEPROP 2 LAST $SEC 1
J 0
(-850 2200);
DISPLAY 0.680851 (-850 2200);
PAINT MONO (-850 2200);
DISPLAY INVISIBLE (-850 2200);
FORCEPROP 2 LAST CDS_SEC 1
J 0
(-850 2200);
DISPLAY 1.021277 (-850 2200);
DISPLAY INVISIBLE (-850 2200);
FORCEPROP 1 LASTPIN (-900 2100) $PN 1
J 0
(-890 2080);
DISPLAY 0.489362 (-890 2080);
FORCEPROP 1 LASTPIN (-900 1900) $PN 2
J 0
(-890 1880);
DISPLAY 0.489362 (-890 1880);
FORCEPROP 1 LAST MATERIAL X6S
J 0
(-850 1900);
DISPLAY 0.489362 (-850 1900);
PAINT SKYBLUE (-850 1900);
FORCEPROP 1 LAST TOLERANCE 20%
J 0
(-850 1950);
DISPLAY 0.489362 (-850 1950);
PAINT SKYBLUE (-850 1950);
FORCEPROP 1 LAST VALUE 22UF
J 0
(-850 2050);
DISPLAY 0.489362 (-850 2050);
PAINT SKYBLUE (-850 2050);
FORCEPROP 1 LAST PART_NUMBER CH622KMEB02
J 0
(-850 1850);
DISPLAY 0.489362 (-850 1850);
PAINT SKYBLUE (-850 1850);
FORCEPROP 1 LAST VOLTAGE 4V
J 0
(-850 2000);
DISPLAY 0.489362 (-850 2000);
PAINT SKYBLUE (-850 2000);
FORCEPROP 1 LAST PACK_TYPE C0402
J 0
(-850 1800);
DISPLAY 0.489362 (-850 1800);
PAINT SKYBLUE (-850 1800);
FORCEPROP 2 LAST CDS_LIB pure_quanta
J 0
(-900 2000);
PAINT MONO (-900 2000);
DISPLAY INVISIBLE (-900 2000);
FORCEPROP 1 LAST PATH I139
J 0
(-850 2150);
DISPLAY 0.978723 (-850 2150);
PAINT WHITE (-850 2150);
DISPLAY INVISIBLE (-850 2150);
FORCEADD UNIVERSAL_POWER..1
(-9075 4000);
FORCEPROP 3 LASTPIN (-9075 3950) SIG_NAME PVDDCR_SOC_P0\g
J 0
(-9065 3960);
DISPLAY 0.659574 (-9065 3960);
PAINT MONO (-9065 3960);
DISPLAY INVISIBLE (-9065 3960);
FORCEPROP 1 LAST HDL_POWER PVDDCR_SOC_P0
J 1
(-9075 4050);
DISPLAY 0.489362 (-9075 4050);
PAINT GREEN (-9075 4050);
FORCEPROP 2 LAST CDS_LIB pure_quanta_power
J 0
(-9075 4000);
DISPLAY INVISIBLE (-9075 4000);
FORCEPROP 1 LAST PATH I14
J 0
(-9025 4025);
DISPLAY 0.872340 (-9025 4025);
PAINT AQUA (-9025 4025);
DISPLAY INVISIBLE (-9025 4025);
FORCEADD Q_CAP..1
(-500 1400);
FORCEPROP 1 LAST LOCATION C3935
J 0
(-450 1500);
DISPLAY 0.489362 (-450 1500);
PAINT SKYBLUE (-450 1500);
FORCEPROP 2 LAST $SEC 1
J 0
(-450 1600);
DISPLAY 0.680851 (-450 1600);
PAINT MONO (-450 1600);
DISPLAY INVISIBLE (-450 1600);
FORCEPROP 2 LAST CDS_SEC 1
J 0
(-450 1600);
DISPLAY 1.021277 (-450 1600);
DISPLAY INVISIBLE (-450 1600);
FORCEPROP 1 LASTPIN (-500 1500) $PN 1
J 0
(-490 1480);
DISPLAY 0.489362 (-490 1480);
FORCEPROP 1 LASTPIN (-500 1300) $PN 2
J 0
(-490 1280);
DISPLAY 0.489362 (-490 1280);
FORCEPROP 1 LAST MATERIAL X6S
J 0
(-450 1300);
DISPLAY 0.489362 (-450 1300);
PAINT SKYBLUE (-450 1300);
FORCEPROP 1 LAST TOLERANCE 20%
J 0
(-450 1350);
DISPLAY 0.489362 (-450 1350);
PAINT SKYBLUE (-450 1350);
FORCEPROP 1 LAST VALUE 22UF
J 0
(-450 1450);
DISPLAY 0.489362 (-450 1450);
PAINT SKYBLUE (-450 1450);
FORCEPROP 1 LAST PART_NUMBER CH622KMEB02
J 0
(-450 1250);
DISPLAY 0.489362 (-450 1250);
PAINT SKYBLUE (-450 1250);
FORCEPROP 1 LAST VOLTAGE 4V
J 0
(-450 1400);
DISPLAY 0.489362 (-450 1400);
PAINT SKYBLUE (-450 1400);
FORCEPROP 1 LAST PACK_TYPE C0402
J 0
(-450 1200);
DISPLAY 0.489362 (-450 1200);
PAINT SKYBLUE (-450 1200);
FORCEPROP 2 LAST CDS_LIB pure_quanta
J 0
(-500 1400);
PAINT MONO (-500 1400);
DISPLAY INVISIBLE (-500 1400);
FORCEPROP 1 LAST PATH I140
J 0
(-450 1550);
DISPLAY 0.978723 (-450 1550);
PAINT WHITE (-450 1550);
DISPLAY INVISIBLE (-450 1550);
FORCEADD UNIVERSAL_GND..1
(-500 1625);
FORCEPROP 3 LASTPIN (-500 1675) SIG_NAME GND\g
J 0
(-490 1685);
DISPLAY 0.659574 (-490 1685);
PAINT MONO (-490 1685);
DISPLAY INVISIBLE (-490 1685);
FORCEPROP 2 LAST CDS_LIB pure_quanta_power
J 0
(-500 1625);
PAINT MONO (-500 1625);
DISPLAY INVISIBLE (-500 1625);
FORCEPROP 1 LAST PATH I141
J 0
(-425 1625);
DISPLAY 0.872340 (-425 1625);
PAINT AQUA (-425 1625);
DISPLAY INVISIBLE (-425 1625);
FORCEPROP 1 LAST HDL_POWER GND
J 1
(-475 1550);
DISPLAY 0.872340 (-475 1550);
PAINT GREEN (-475 1550);
DISPLAY INVISIBLE (-475 1550);
FORCEADD Q_CAP..1
(-500 2000);
FORCEPROP 1 LAST LOCATION C2658
J 0
(-450 2100);
DISPLAY 0.489362 (-450 2100);
PAINT SKYBLUE (-450 2100);
FORCEPROP 2 LAST $SEC 1
J 0
(-450 2200);
DISPLAY 0.680851 (-450 2200);
PAINT MONO (-450 2200);
DISPLAY INVISIBLE (-450 2200);
FORCEPROP 2 LAST CDS_SEC 1
J 0
(-450 2200);
DISPLAY 1.021277 (-450 2200);
DISPLAY INVISIBLE (-450 2200);
FORCEPROP 1 LASTPIN (-500 2100) $PN 1
J 0
(-490 2080);
DISPLAY 0.489362 (-490 2080);
FORCEPROP 1 LASTPIN (-500 1900) $PN 2
J 0
(-490 1880);
DISPLAY 0.489362 (-490 1880);
FORCEPROP 1 LAST MATERIAL X6S
J 0
(-450 1900);
DISPLAY 0.489362 (-450 1900);
PAINT SKYBLUE (-450 1900);
FORCEPROP 1 LAST TOLERANCE 20%
J 0
(-450 1950);
DISPLAY 0.489362 (-450 1950);
PAINT SKYBLUE (-450 1950);
FORCEPROP 1 LAST VALUE 22UF
J 0
(-450 2050);
DISPLAY 0.489362 (-450 2050);
PAINT SKYBLUE (-450 2050);
FORCEPROP 1 LAST PART_NUMBER CH622KMEB02
J 0
(-450 1850);
DISPLAY 0.489362 (-450 1850);
PAINT SKYBLUE (-450 1850);
FORCEPROP 1 LAST VOLTAGE 4V
J 0
(-450 2000);
DISPLAY 0.489362 (-450 2000);
PAINT SKYBLUE (-450 2000);
FORCEPROP 1 LAST PACK_TYPE C0402
J 0
(-450 1800);
DISPLAY 0.489362 (-450 1800);
PAINT SKYBLUE (-450 1800);
FORCEPROP 2 LAST CDS_LIB pure_quanta
J 0
(-500 2000);
PAINT MONO (-500 2000);
DISPLAY INVISIBLE (-500 2000);
FORCEPROP 1 LAST PATH I142
J 0
(-450 2150);
DISPLAY 0.978723 (-450 2150);
PAINT WHITE (-450 2150);
DISPLAY INVISIBLE (-450 2150);
FORCEADD Q_CAP..1
(-1800 2625);
FORCEPROP 1 LAST LOCATION C2640
J 0
(-1750 2725);
DISPLAY 0.489362 (-1750 2725);
PAINT SKYBLUE (-1750 2725);
FORCEPROP 2 LAST $SEC 1
J 0
(-1750 2825);
DISPLAY 0.680851 (-1750 2825);
PAINT MONO (-1750 2825);
DISPLAY INVISIBLE (-1750 2825);
FORCEPROP 2 LAST CDS_SEC 1
J 0
(-1750 2825);
DISPLAY 1.021277 (-1750 2825);
DISPLAY INVISIBLE (-1750 2825);
FORCEPROP 1 LASTPIN (-1800 2725) $PN 1
J 0
(-1790 2705);
DISPLAY 0.489362 (-1790 2705);
FORCEPROP 1 LASTPIN (-1800 2525) $PN 2
J 0
(-1790 2505);
DISPLAY 0.489362 (-1790 2505);
FORCEPROP 1 LAST MATERIAL X6S
J 0
(-1750 2525);
DISPLAY 0.489362 (-1750 2525);
PAINT SKYBLUE (-1750 2525);
FORCEPROP 1 LAST TOLERANCE 20%
J 0
(-1750 2575);
DISPLAY 0.489362 (-1750 2575);
PAINT SKYBLUE (-1750 2575);
FORCEPROP 1 LAST VALUE 22UF
J 0
(-1750 2675);
DISPLAY 0.489362 (-1750 2675);
PAINT SKYBLUE (-1750 2675);
FORCEPROP 1 LAST PART_NUMBER CH622KMEB02
J 0
(-1750 2475);
DISPLAY 0.489362 (-1750 2475);
PAINT SKYBLUE (-1750 2475);
FORCEPROP 1 LAST VOLTAGE 4V
J 0
(-1750 2625);
DISPLAY 0.489362 (-1750 2625);
PAINT SKYBLUE (-1750 2625);
FORCEPROP 1 LAST PACK_TYPE C0402
J 0
(-1750 2425);
DISPLAY 0.489362 (-1750 2425);
PAINT SKYBLUE (-1750 2425);
FORCEPROP 2 LAST CDS_LIB pure_quanta
J 0
(-1800 2625);
PAINT MONO (-1800 2625);
DISPLAY INVISIBLE (-1800 2625);
FORCEPROP 1 LAST PATH I143
J 0
(-1750 2775);
DISPLAY 0.978723 (-1750 2775);
PAINT WHITE (-1750 2775);
DISPLAY INVISIBLE (-1750 2775);
FORCEADD Q_CAP..1
(-1350 2625);
FORCEPROP 1 LAST LOCATION C2646
J 0
(-1300 2725);
DISPLAY 0.489362 (-1300 2725);
PAINT SKYBLUE (-1300 2725);
FORCEPROP 2 LAST $SEC 1
J 0
(-1300 2825);
DISPLAY 0.680851 (-1300 2825);
PAINT MONO (-1300 2825);
DISPLAY INVISIBLE (-1300 2825);
FORCEPROP 2 LAST CDS_SEC 1
J 0
(-1300 2825);
DISPLAY 1.021277 (-1300 2825);
DISPLAY INVISIBLE (-1300 2825);
FORCEPROP 1 LASTPIN (-1350 2725) $PN 1
J 0
(-1340 2705);
DISPLAY 0.489362 (-1340 2705);
FORCEPROP 1 LASTPIN (-1350 2525) $PN 2
J 0
(-1340 2505);
DISPLAY 0.489362 (-1340 2505);
FORCEPROP 1 LAST MATERIAL X6S
J 0
(-1300 2525);
DISPLAY 0.489362 (-1300 2525);
PAINT SKYBLUE (-1300 2525);
FORCEPROP 1 LAST TOLERANCE 20%
J 0
(-1300 2575);
DISPLAY 0.489362 (-1300 2575);
PAINT SKYBLUE (-1300 2575);
FORCEPROP 1 LAST VALUE 22UF
J 0
(-1300 2675);
DISPLAY 0.489362 (-1300 2675);
PAINT SKYBLUE (-1300 2675);
FORCEPROP 1 LAST PART_NUMBER CH622KMEB02
J 0
(-1300 2475);
DISPLAY 0.489362 (-1300 2475);
PAINT SKYBLUE (-1300 2475);
FORCEPROP 1 LAST VOLTAGE 4V
J 0
(-1300 2625);
DISPLAY 0.489362 (-1300 2625);
PAINT SKYBLUE (-1300 2625);
FORCEPROP 1 LAST PACK_TYPE C0402
J 0
(-1300 2425);
DISPLAY 0.489362 (-1300 2425);
PAINT SKYBLUE (-1300 2425);
FORCEPROP 2 LAST CDS_LIB pure_quanta
J 0
(-1350 2625);
PAINT MONO (-1350 2625);
DISPLAY INVISIBLE (-1350 2625);
FORCEPROP 1 LAST PATH I144
J 0
(-1300 2775);
DISPLAY 0.978723 (-1300 2775);
PAINT WHITE (-1300 2775);
DISPLAY INVISIBLE (-1300 2775);
FORCEADD Q_CAP..1
(-1800 3275);
FORCEPROP 1 LAST LOCATION C2639
J 0
(-1750 3375);
DISPLAY 0.489362 (-1750 3375);
PAINT SKYBLUE (-1750 3375);
FORCEPROP 2 LAST $SEC 1
J 0
(-1750 3475);
DISPLAY 0.680851 (-1750 3475);
PAINT MONO (-1750 3475);
DISPLAY INVISIBLE (-1750 3475);
FORCEPROP 2 LAST CDS_SEC 1
J 0
(-1750 3475);
DISPLAY 1.021277 (-1750 3475);
DISPLAY INVISIBLE (-1750 3475);
FORCEPROP 1 LASTPIN (-1800 3375) $PN 1
J 0
(-1790 3355);
DISPLAY 0.489362 (-1790 3355);
FORCEPROP 1 LASTPIN (-1800 3175) $PN 2
J 0
(-1790 3155);
DISPLAY 0.489362 (-1790 3155);
FORCEPROP 1 LAST MATERIAL X6S
J 0
(-1750 3175);
DISPLAY 0.489362 (-1750 3175);
PAINT SKYBLUE (-1750 3175);
FORCEPROP 1 LAST TOLERANCE 20%
J 0
(-1750 3225);
DISPLAY 0.489362 (-1750 3225);
PAINT SKYBLUE (-1750 3225);
FORCEPROP 1 LAST VALUE 22UF
J 0
(-1750 3325);
DISPLAY 0.489362 (-1750 3325);
PAINT SKYBLUE (-1750 3325);
FORCEPROP 1 LAST PART_NUMBER CH622KMEB02
J 0
(-1750 3125);
DISPLAY 0.489362 (-1750 3125);
PAINT SKYBLUE (-1750 3125);
FORCEPROP 1 LAST VOLTAGE 4V
J 0
(-1750 3275);
DISPLAY 0.489362 (-1750 3275);
PAINT SKYBLUE (-1750 3275);
FORCEPROP 1 LAST PACK_TYPE C0402
J 0
(-1750 3075);
DISPLAY 0.489362 (-1750 3075);
PAINT SKYBLUE (-1750 3075);
FORCEPROP 2 LAST CDS_LIB pure_quanta
J 0
(-1800 3275);
PAINT MONO (-1800 3275);
DISPLAY INVISIBLE (-1800 3275);
FORCEPROP 1 LAST PATH I145
J 0
(-1750 3425);
DISPLAY 0.978723 (-1750 3425);
PAINT WHITE (-1750 3425);
DISPLAY INVISIBLE (-1750 3425);
FORCEADD Q_CAP..1
(-1350 3275);
FORCEPROP 1 LAST LOCATION C2645
J 0
(-1300 3375);
DISPLAY 0.489362 (-1300 3375);
PAINT SKYBLUE (-1300 3375);
FORCEPROP 2 LAST $SEC 1
J 0
(-1300 3475);
DISPLAY 0.680851 (-1300 3475);
PAINT MONO (-1300 3475);
DISPLAY INVISIBLE (-1300 3475);
FORCEPROP 2 LAST CDS_SEC 1
J 0
(-1300 3475);
DISPLAY 1.021277 (-1300 3475);
DISPLAY INVISIBLE (-1300 3475);
FORCEPROP 1 LASTPIN (-1350 3375) $PN 1
J 0
(-1340 3355);
DISPLAY 0.489362 (-1340 3355);
FORCEPROP 1 LASTPIN (-1350 3175) $PN 2
J 0
(-1340 3155);
DISPLAY 0.489362 (-1340 3155);
FORCEPROP 1 LAST MATERIAL X6S
J 0
(-1300 3175);
DISPLAY 0.489362 (-1300 3175);
PAINT SKYBLUE (-1300 3175);
FORCEPROP 1 LAST TOLERANCE 20%
J 0
(-1300 3225);
DISPLAY 0.489362 (-1300 3225);
PAINT SKYBLUE (-1300 3225);
FORCEPROP 1 LAST VALUE 22UF
J 0
(-1300 3325);
DISPLAY 0.489362 (-1300 3325);
PAINT SKYBLUE (-1300 3325);
FORCEPROP 1 LAST PART_NUMBER CH622KMEB02
J 0
(-1300 3125);
DISPLAY 0.489362 (-1300 3125);
PAINT SKYBLUE (-1300 3125);
FORCEPROP 1 LAST VOLTAGE 4V
J 0
(-1300 3275);
DISPLAY 0.489362 (-1300 3275);
PAINT SKYBLUE (-1300 3275);
FORCEPROP 1 LAST PACK_TYPE C0402
J 0
(-1300 3075);
DISPLAY 0.489362 (-1300 3075);
PAINT SKYBLUE (-1300 3075);
FORCEPROP 2 LAST CDS_LIB pure_quanta
J 0
(-1350 3275);
PAINT MONO (-1350 3275);
DISPLAY INVISIBLE (-1350 3275);
FORCEPROP 1 LAST PATH I146
J 0
(-1300 3425);
DISPLAY 0.978723 (-1300 3425);
PAINT WHITE (-1300 3425);
DISPLAY INVISIBLE (-1300 3425);
FORCEADD Q_CAP..1
(-900 2625);
FORCEPROP 1 LAST LOCATION C2652
J 0
(-850 2725);
DISPLAY 0.489362 (-850 2725);
PAINT SKYBLUE (-850 2725);
FORCEPROP 2 LAST $SEC 1
J 0
(-850 2825);
DISPLAY 0.680851 (-850 2825);
PAINT MONO (-850 2825);
DISPLAY INVISIBLE (-850 2825);
FORCEPROP 2 LAST CDS_SEC 1
J 0
(-850 2825);
DISPLAY 1.021277 (-850 2825);
DISPLAY INVISIBLE (-850 2825);
FORCEPROP 1 LASTPIN (-900 2725) $PN 1
J 0
(-890 2705);
DISPLAY 0.489362 (-890 2705);
FORCEPROP 1 LASTPIN (-900 2525) $PN 2
J 0
(-890 2505);
DISPLAY 0.489362 (-890 2505);
FORCEPROP 1 LAST MATERIAL X6S
J 0
(-850 2525);
DISPLAY 0.489362 (-850 2525);
PAINT SKYBLUE (-850 2525);
FORCEPROP 1 LAST TOLERANCE 20%
J 0
(-850 2575);
DISPLAY 0.489362 (-850 2575);
PAINT SKYBLUE (-850 2575);
FORCEPROP 1 LAST VALUE 22UF
J 0
(-850 2675);
DISPLAY 0.489362 (-850 2675);
PAINT SKYBLUE (-850 2675);
FORCEPROP 1 LAST PART_NUMBER CH622KMEB02
J 0
(-850 2475);
DISPLAY 0.489362 (-850 2475);
PAINT SKYBLUE (-850 2475);
FORCEPROP 1 LAST VOLTAGE 4V
J 0
(-850 2625);
DISPLAY 0.489362 (-850 2625);
PAINT SKYBLUE (-850 2625);
FORCEPROP 1 LAST PACK_TYPE C0402
J 0
(-850 2425);
DISPLAY 0.489362 (-850 2425);
PAINT SKYBLUE (-850 2425);
FORCEPROP 2 LAST CDS_LIB pure_quanta
J 0
(-900 2625);
PAINT MONO (-900 2625);
DISPLAY INVISIBLE (-900 2625);
FORCEPROP 1 LAST PATH I147
J 0
(-850 2775);
DISPLAY 0.978723 (-850 2775);
PAINT WHITE (-850 2775);
DISPLAY INVISIBLE (-850 2775);
FORCEADD UNIVERSAL_GND..1
(-500 2275);
FORCEPROP 3 LASTPIN (-500 2325) SIG_NAME GND\g
J 0
(-490 2335);
DISPLAY 0.659574 (-490 2335);
PAINT MONO (-490 2335);
DISPLAY INVISIBLE (-490 2335);
FORCEPROP 2 LAST CDS_LIB pure_quanta_power
J 0
(-500 2275);
PAINT MONO (-500 2275);
DISPLAY INVISIBLE (-500 2275);
FORCEPROP 1 LAST PATH I148
J 0
(-425 2275);
DISPLAY 0.872340 (-425 2275);
PAINT AQUA (-425 2275);
DISPLAY INVISIBLE (-425 2275);
FORCEPROP 1 LAST HDL_POWER GND
J 1
(-475 2200);
DISPLAY 0.872340 (-475 2200);
PAINT GREEN (-475 2200);
DISPLAY INVISIBLE (-475 2200);
FORCEADD Q_CAP..1
(-500 2625);
FORCEPROP 1 LAST LOCATION C2657
J 0
(-450 2725);
DISPLAY 0.489362 (-450 2725);
PAINT SKYBLUE (-450 2725);
FORCEPROP 2 LAST $SEC 1
J 0
(-450 2825);
DISPLAY 0.680851 (-450 2825);
PAINT MONO (-450 2825);
DISPLAY INVISIBLE (-450 2825);
FORCEPROP 2 LAST CDS_SEC 1
J 0
(-450 2825);
DISPLAY 1.021277 (-450 2825);
DISPLAY INVISIBLE (-450 2825);
FORCEPROP 1 LASTPIN (-500 2725) $PN 1
J 0
(-490 2705);
DISPLAY 0.489362 (-490 2705);
FORCEPROP 1 LASTPIN (-500 2525) $PN 2
J 0
(-490 2505);
DISPLAY 0.489362 (-490 2505);
FORCEPROP 1 LAST MATERIAL X6S
J 0
(-450 2525);
DISPLAY 0.489362 (-450 2525);
PAINT SKYBLUE (-450 2525);
FORCEPROP 1 LAST TOLERANCE 20%
J 0
(-450 2575);
DISPLAY 0.489362 (-450 2575);
PAINT SKYBLUE (-450 2575);
FORCEPROP 1 LAST VALUE 22UF
J 0
(-450 2675);
DISPLAY 0.489362 (-450 2675);
PAINT SKYBLUE (-450 2675);
FORCEPROP 1 LAST PART_NUMBER CH622KMEB02
J 0
(-450 2475);
DISPLAY 0.489362 (-450 2475);
PAINT SKYBLUE (-450 2475);
FORCEPROP 1 LAST VOLTAGE 4V
J 0
(-450 2625);
DISPLAY 0.489362 (-450 2625);
PAINT SKYBLUE (-450 2625);
FORCEPROP 1 LAST PACK_TYPE C0402
J 0
(-450 2425);
DISPLAY 0.489362 (-450 2425);
PAINT SKYBLUE (-450 2425);
FORCEPROP 2 LAST CDS_LIB pure_quanta
J 0
(-500 2625);
PAINT MONO (-500 2625);
DISPLAY INVISIBLE (-500 2625);
FORCEPROP 1 LAST PATH I149
J 0
(-450 2775);
DISPLAY 0.978723 (-450 2775);
PAINT WHITE (-450 2775);
DISPLAY INVISIBLE (-450 2775);
FORCEADD Q_CAP..1
(-8625 3725);
FORCEPROP 1 LAST LOCATION C2537
J 0
(-8575 3825);
DISPLAY 0.489362 (-8575 3825);
PAINT SKYBLUE (-8575 3825);
FORCEPROP 2 LAST $SEC 1
J 0
(-8575 3925);
DISPLAY 0.680851 (-8575 3925);
PAINT MONO (-8575 3925);
DISPLAY INVISIBLE (-8575 3925);
FORCEPROP 2 LAST CDS_SEC 1
J 0
(-8575 3925);
DISPLAY 1.021277 (-8575 3925);
DISPLAY INVISIBLE (-8575 3925);
FORCEPROP 1 LASTPIN (-8625 3825) $PN 1
J 0
(-8615 3805);
DISPLAY 0.489362 (-8615 3805);
FORCEPROP 1 LASTPIN (-8625 3625) $PN 2
J 0
(-8615 3605);
DISPLAY 0.489362 (-8615 3605);
FORCEPROP 1 LAST MATERIAL X6S
J 0
(-8575 3625);
DISPLAY 0.489362 (-8575 3625);
PAINT SKYBLUE (-8575 3625);
FORCEPROP 1 LAST TOLERANCE 20%
J 0
(-8575 3675);
DISPLAY 0.489362 (-8575 3675);
PAINT SKYBLUE (-8575 3675);
FORCEPROP 1 LAST VALUE 22UF
J 0
(-8575 3775);
DISPLAY 0.489362 (-8575 3775);
PAINT SKYBLUE (-8575 3775);
FORCEPROP 1 LAST PART_NUMBER CH622KMEB02
J 0
(-8575 3575);
DISPLAY 0.489362 (-8575 3575);
PAINT SKYBLUE (-8575 3575);
FORCEPROP 1 LAST VOLTAGE 4V
J 0
(-8575 3725);
DISPLAY 0.489362 (-8575 3725);
PAINT SKYBLUE (-8575 3725);
FORCEPROP 1 LAST PACK_TYPE C0402
J 0
(-8575 3525);
DISPLAY 0.489362 (-8575 3525);
PAINT SKYBLUE (-8575 3525);
FORCEPROP 2 LAST CDS_LIB pure_quanta
J 0
(-8625 3725);
PAINT MONO (-8625 3725);
DISPLAY INVISIBLE (-8625 3725);
FORCEPROP 1 LAST PATH I15
J 0
(-8575 3875);
DISPLAY 0.978723 (-8575 3875);
PAINT WHITE (-8575 3875);
DISPLAY INVISIBLE (-8575 3875);
FORCEADD UNIVERSAL_GND..1
(-500 2900);
FORCEPROP 3 LASTPIN (-500 2950) SIG_NAME GND\g
J 0
(-490 2960);
DISPLAY 0.659574 (-490 2960);
PAINT MONO (-490 2960);
DISPLAY INVISIBLE (-490 2960);
FORCEPROP 2 LAST CDS_LIB pure_quanta_power
J 0
(-500 2900);
PAINT MONO (-500 2900);
DISPLAY INVISIBLE (-500 2900);
FORCEPROP 1 LAST PATH I150
J 0
(-425 2900);
DISPLAY 0.872340 (-425 2900);
PAINT AQUA (-425 2900);
DISPLAY INVISIBLE (-425 2900);
FORCEPROP 1 LAST HDL_POWER GND
J 1
(-475 2825);
DISPLAY 0.872340 (-475 2825);
PAINT GREEN (-475 2825);
DISPLAY INVISIBLE (-475 2825);
FORCEADD Q_CAP..1
(-900 3275);
FORCEPROP 1 LAST LOCATION C2651
J 0
(-850 3375);
DISPLAY 0.489362 (-850 3375);
PAINT SKYBLUE (-850 3375);
FORCEPROP 2 LAST $SEC 1
J 0
(-850 3475);
DISPLAY 0.680851 (-850 3475);
PAINT MONO (-850 3475);
DISPLAY INVISIBLE (-850 3475);
FORCEPROP 2 LAST CDS_SEC 1
J 0
(-850 3475);
DISPLAY 1.021277 (-850 3475);
DISPLAY INVISIBLE (-850 3475);
FORCEPROP 1 LASTPIN (-900 3375) $PN 1
J 0
(-890 3355);
DISPLAY 0.489362 (-890 3355);
FORCEPROP 1 LASTPIN (-900 3175) $PN 2
J 0
(-890 3155);
DISPLAY 0.489362 (-890 3155);
FORCEPROP 1 LAST MATERIAL X6S
J 0
(-850 3175);
DISPLAY 0.489362 (-850 3175);
PAINT SKYBLUE (-850 3175);
FORCEPROP 1 LAST TOLERANCE 20%
J 0
(-850 3225);
DISPLAY 0.489362 (-850 3225);
PAINT SKYBLUE (-850 3225);
FORCEPROP 1 LAST VALUE 22UF
J 0
(-850 3325);
DISPLAY 0.489362 (-850 3325);
PAINT SKYBLUE (-850 3325);
FORCEPROP 1 LAST PART_NUMBER CH622KMEB02
J 0
(-850 3125);
DISPLAY 0.489362 (-850 3125);
PAINT SKYBLUE (-850 3125);
FORCEPROP 1 LAST VOLTAGE 4V
J 0
(-850 3275);
DISPLAY 0.489362 (-850 3275);
PAINT SKYBLUE (-850 3275);
FORCEPROP 1 LAST PACK_TYPE C0402
J 0
(-850 3075);
DISPLAY 0.489362 (-850 3075);
PAINT SKYBLUE (-850 3075);
FORCEPROP 2 LAST CDS_LIB pure_quanta
J 0
(-900 3275);
PAINT MONO (-900 3275);
DISPLAY INVISIBLE (-900 3275);
FORCEPROP 1 LAST PATH I151
J 0
(-850 3425);
DISPLAY 0.978723 (-850 3425);
PAINT WHITE (-850 3425);
DISPLAY INVISIBLE (-850 3425);
FORCEADD Q_CAP..1
(-500 3275);
FORCEPROP 1 LAST LOCATION C2656
J 0
(-450 3375);
DISPLAY 0.489362 (-450 3375);
PAINT SKYBLUE (-450 3375);
FORCEPROP 2 LAST $SEC 1
J 0
(-450 3475);
DISPLAY 0.680851 (-450 3475);
PAINT MONO (-450 3475);
DISPLAY INVISIBLE (-450 3475);
FORCEPROP 2 LAST CDS_SEC 1
J 0
(-450 3475);
DISPLAY 1.021277 (-450 3475);
DISPLAY INVISIBLE (-450 3475);
FORCEPROP 1 LASTPIN (-500 3375) $PN 1
J 0
(-490 3355);
DISPLAY 0.489362 (-490 3355);
FORCEPROP 1 LASTPIN (-500 3175) $PN 2
J 0
(-490 3155);
DISPLAY 0.489362 (-490 3155);
FORCEPROP 1 LAST MATERIAL X6S
J 0
(-450 3175);
DISPLAY 0.489362 (-450 3175);
PAINT SKYBLUE (-450 3175);
FORCEPROP 1 LAST TOLERANCE 20%
J 0
(-450 3225);
DISPLAY 0.489362 (-450 3225);
PAINT SKYBLUE (-450 3225);
FORCEPROP 1 LAST VALUE 22UF
J 0
(-450 3325);
DISPLAY 0.489362 (-450 3325);
PAINT SKYBLUE (-450 3325);
FORCEPROP 1 LAST PART_NUMBER CH622KMEB02
J 0
(-450 3125);
DISPLAY 0.489362 (-450 3125);
PAINT SKYBLUE (-450 3125);
FORCEPROP 1 LAST VOLTAGE 4V
J 0
(-450 3275);
DISPLAY 0.489362 (-450 3275);
PAINT SKYBLUE (-450 3275);
FORCEPROP 1 LAST PACK_TYPE C0402
J 0
(-450 3075);
DISPLAY 0.489362 (-450 3075);
PAINT SKYBLUE (-450 3075);
FORCEPROP 2 LAST CDS_LIB pure_quanta
J 0
(-500 3275);
PAINT MONO (-500 3275);
DISPLAY INVISIBLE (-500 3275);
FORCEPROP 1 LAST PATH I152
J 0
(-450 3425);
DISPLAY 0.978723 (-450 3425);
PAINT WHITE (-450 3425);
DISPLAY INVISIBLE (-450 3425);
FORCEADD Q_CAP..1
(-4050 4325);
FORCEPROP 1 LAST LOCATION C2606
J 0
(-4000 4425);
DISPLAY 0.489362 (-4000 4425);
PAINT SKYBLUE (-4000 4425);
FORCEPROP 2 LAST $SEC 1
J 0
(-4000 4525);
DISPLAY 0.680851 (-4000 4525);
PAINT MONO (-4000 4525);
DISPLAY INVISIBLE (-4000 4525);
FORCEPROP 2 LAST CDS_SEC 1
J 0
(-4000 4525);
DISPLAY 1.021277 (-4000 4525);
DISPLAY INVISIBLE (-4000 4525);
FORCEPROP 1 LASTPIN (-4050 4425) $PN 1
J 0
(-4040 4405);
DISPLAY 0.489362 (-4040 4405);
FORCEPROP 1 LASTPIN (-4050 4225) $PN 2
J 0
(-4040 4205);
DISPLAY 0.489362 (-4040 4205);
FORCEPROP 1 LAST MATERIAL X6S
J 0
(-4000 4225);
DISPLAY 0.489362 (-4000 4225);
PAINT SKYBLUE (-4000 4225);
FORCEPROP 1 LAST TOLERANCE 20%
J 0
(-4000 4275);
DISPLAY 0.489362 (-4000 4275);
PAINT SKYBLUE (-4000 4275);
FORCEPROP 1 LAST VALUE 22UF
J 0
(-4000 4375);
DISPLAY 0.489362 (-4000 4375);
PAINT SKYBLUE (-4000 4375);
FORCEPROP 1 LAST PART_NUMBER CH622KMEB02
J 0
(-4000 4175);
DISPLAY 0.489362 (-4000 4175);
PAINT SKYBLUE (-4000 4175);
FORCEPROP 1 LAST VOLTAGE 4V
J 0
(-4000 4325);
DISPLAY 0.489362 (-4000 4325);
PAINT SKYBLUE (-4000 4325);
FORCEPROP 1 LAST PACK_TYPE C0402
J 0
(-4000 4125);
DISPLAY 0.489362 (-4000 4125);
PAINT SKYBLUE (-4000 4125);
FORCEPROP 2 LAST CDS_LIB pure_quanta
J 0
(-4050 4325);
PAINT MONO (-4050 4325);
DISPLAY INVISIBLE (-4050 4325);
FORCEPROP 1 LAST PATH I153
J 0
(-4000 4475);
DISPLAY 0.978723 (-4000 4475);
PAINT WHITE (-4000 4475);
DISPLAY INVISIBLE (-4000 4475);
FORCEADD Q_CAP..1
(-4075 5100);
FORCEPROP 1 LAST LOCATION C2605
J 0
(-4025 5200);
DISPLAY 0.489362 (-4025 5200);
PAINT SKYBLUE (-4025 5200);
FORCEPROP 2 LAST $SEC 1
J 0
(-4025 5300);
DISPLAY 0.680851 (-4025 5300);
PAINT MONO (-4025 5300);
DISPLAY INVISIBLE (-4025 5300);
FORCEPROP 2 LAST CDS_SEC 1
J 0
(-4025 5300);
DISPLAY 1.021277 (-4025 5300);
DISPLAY INVISIBLE (-4025 5300);
FORCEPROP 1 LASTPIN (-4075 5200) $PN 1
J 0
(-4065 5180);
DISPLAY 0.489362 (-4065 5180);
FORCEPROP 1 LASTPIN (-4075 5000) $PN 2
J 0
(-4065 4980);
DISPLAY 0.489362 (-4065 4980);
FORCEPROP 1 LAST MATERIAL X6S
J 0
(-4025 5000);
DISPLAY 0.489362 (-4025 5000);
PAINT SKYBLUE (-4025 5000);
FORCEPROP 1 LAST TOLERANCE 20%
J 0
(-4025 5050);
DISPLAY 0.489362 (-4025 5050);
PAINT SKYBLUE (-4025 5050);
FORCEPROP 1 LAST VALUE 22UF
J 0
(-4025 5150);
DISPLAY 0.489362 (-4025 5150);
PAINT SKYBLUE (-4025 5150);
FORCEPROP 1 LAST PART_NUMBER CH622KMEB02
J 0
(-4025 4950);
DISPLAY 0.489362 (-4025 4950);
PAINT SKYBLUE (-4025 4950);
FORCEPROP 1 LAST VOLTAGE 4V
J 0
(-4025 5100);
DISPLAY 0.489362 (-4025 5100);
PAINT SKYBLUE (-4025 5100);
FORCEPROP 1 LAST PACK_TYPE C0402
J 0
(-4025 4900);
DISPLAY 0.489362 (-4025 4900);
PAINT SKYBLUE (-4025 4900);
FORCEPROP 2 LAST CDS_LIB pure_quanta
J 0
(-4075 5100);
PAINT MONO (-4075 5100);
DISPLAY INVISIBLE (-4075 5100);
FORCEPROP 1 LAST PATH I154
J 0
(-4025 5250);
DISPLAY 0.978723 (-4025 5250);
PAINT WHITE (-4025 5250);
DISPLAY INVISIBLE (-4025 5250);
FORCEADD Q_CAP..1
(-3600 4325);
FORCEPROP 1 LAST LOCATION C2613
J 0
(-3550 4425);
DISPLAY 0.489362 (-3550 4425);
PAINT SKYBLUE (-3550 4425);
FORCEPROP 2 LAST $SEC 1
J 0
(-3550 4525);
DISPLAY 0.680851 (-3550 4525);
PAINT MONO (-3550 4525);
DISPLAY INVISIBLE (-3550 4525);
FORCEPROP 2 LAST CDS_SEC 1
J 0
(-3550 4525);
DISPLAY 1.021277 (-3550 4525);
DISPLAY INVISIBLE (-3550 4525);
FORCEPROP 1 LASTPIN (-3600 4425) $PN 1
J 0
(-3590 4405);
DISPLAY 0.489362 (-3590 4405);
FORCEPROP 1 LASTPIN (-3600 4225) $PN 2
J 0
(-3590 4205);
DISPLAY 0.489362 (-3590 4205);
FORCEPROP 1 LAST MATERIAL X6S
J 0
(-3550 4225);
DISPLAY 0.489362 (-3550 4225);
PAINT SKYBLUE (-3550 4225);
FORCEPROP 1 LAST TOLERANCE 20%
J 0
(-3550 4275);
DISPLAY 0.489362 (-3550 4275);
PAINT SKYBLUE (-3550 4275);
FORCEPROP 1 LAST VALUE 22UF
J 0
(-3550 4375);
DISPLAY 0.489362 (-3550 4375);
PAINT SKYBLUE (-3550 4375);
FORCEPROP 1 LAST PART_NUMBER CH622KMEB02
J 0
(-3550 4175);
DISPLAY 0.489362 (-3550 4175);
PAINT SKYBLUE (-3550 4175);
FORCEPROP 1 LAST VOLTAGE 4V
J 0
(-3550 4325);
DISPLAY 0.489362 (-3550 4325);
PAINT SKYBLUE (-3550 4325);
FORCEPROP 1 LAST PACK_TYPE C0402
J 0
(-3550 4125);
DISPLAY 0.489362 (-3550 4125);
PAINT SKYBLUE (-3550 4125);
FORCEPROP 2 LAST CDS_LIB pure_quanta
J 0
(-3600 4325);
PAINT MONO (-3600 4325);
DISPLAY INVISIBLE (-3600 4325);
FORCEPROP 1 LAST PATH I155
J 0
(-3550 4475);
DISPLAY 0.978723 (-3550 4475);
PAINT WHITE (-3550 4475);
DISPLAY INVISIBLE (-3550 4475);
FORCEADD Q_CAP..1
(-3625 5100);
FORCEPROP 1 LAST LOCATION C2612
J 0
(-3575 5200);
DISPLAY 0.489362 (-3575 5200);
PAINT SKYBLUE (-3575 5200);
FORCEPROP 2 LAST $SEC 1
J 0
(-3575 5300);
DISPLAY 0.680851 (-3575 5300);
PAINT MONO (-3575 5300);
DISPLAY INVISIBLE (-3575 5300);
FORCEPROP 2 LAST CDS_SEC 1
J 0
(-3575 5300);
DISPLAY 1.021277 (-3575 5300);
DISPLAY INVISIBLE (-3575 5300);
FORCEPROP 1 LASTPIN (-3625 5200) $PN 1
J 0
(-3615 5180);
DISPLAY 0.489362 (-3615 5180);
FORCEPROP 1 LASTPIN (-3625 5000) $PN 2
J 0
(-3615 4980);
DISPLAY 0.489362 (-3615 4980);
FORCEPROP 1 LAST MATERIAL X6S
J 0
(-3575 5000);
DISPLAY 0.489362 (-3575 5000);
PAINT SKYBLUE (-3575 5000);
FORCEPROP 1 LAST TOLERANCE 20%
J 0
(-3575 5050);
DISPLAY 0.489362 (-3575 5050);
PAINT SKYBLUE (-3575 5050);
FORCEPROP 1 LAST VALUE 22UF
J 0
(-3575 5150);
DISPLAY 0.489362 (-3575 5150);
PAINT SKYBLUE (-3575 5150);
FORCEPROP 1 LAST PART_NUMBER CH622KMEB02
J 0
(-3575 4950);
DISPLAY 0.489362 (-3575 4950);
PAINT SKYBLUE (-3575 4950);
FORCEPROP 1 LAST VOLTAGE 4V
J 0
(-3575 5100);
DISPLAY 0.489362 (-3575 5100);
PAINT SKYBLUE (-3575 5100);
FORCEPROP 1 LAST PACK_TYPE C0402
J 0
(-3575 4900);
DISPLAY 0.489362 (-3575 4900);
PAINT SKYBLUE (-3575 4900);
FORCEPROP 2 LAST CDS_LIB pure_quanta
J 0
(-3625 5100);
PAINT MONO (-3625 5100);
DISPLAY INVISIBLE (-3625 5100);
FORCEPROP 1 LAST PATH I156
J 0
(-3575 5250);
DISPLAY 0.978723 (-3575 5250);
PAINT WHITE (-3575 5250);
DISPLAY INVISIBLE (-3575 5250);
FORCEADD Q_CAP..1
(-3175 5100);
FORCEPROP 1 LAST LOCATION C2619
J 0
(-3125 5200);
DISPLAY 0.489362 (-3125 5200);
PAINT SKYBLUE (-3125 5200);
FORCEPROP 2 LAST $SEC 1
J 0
(-3125 5300);
DISPLAY 0.680851 (-3125 5300);
PAINT MONO (-3125 5300);
DISPLAY INVISIBLE (-3125 5300);
FORCEPROP 2 LAST CDS_SEC 1
J 0
(-3125 5300);
DISPLAY 1.021277 (-3125 5300);
DISPLAY INVISIBLE (-3125 5300);
FORCEPROP 1 LASTPIN (-3175 5200) $PN 1
J 0
(-3165 5180);
DISPLAY 0.489362 (-3165 5180);
FORCEPROP 1 LASTPIN (-3175 5000) $PN 2
J 0
(-3165 4980);
DISPLAY 0.489362 (-3165 4980);
FORCEPROP 1 LAST MATERIAL X6S
J 0
(-3125 5000);
DISPLAY 0.489362 (-3125 5000);
PAINT SKYBLUE (-3125 5000);
FORCEPROP 1 LAST TOLERANCE 20%
J 0
(-3125 5050);
DISPLAY 0.489362 (-3125 5050);
PAINT SKYBLUE (-3125 5050);
FORCEPROP 1 LAST VALUE 22UF
J 0
(-3125 5150);
DISPLAY 0.489362 (-3125 5150);
PAINT SKYBLUE (-3125 5150);
FORCEPROP 1 LAST PART_NUMBER CH622KMEB02
J 0
(-3125 4950);
DISPLAY 0.489362 (-3125 4950);
PAINT SKYBLUE (-3125 4950);
FORCEPROP 1 LAST VOLTAGE 4V
J 0
(-3125 5100);
DISPLAY 0.489362 (-3125 5100);
PAINT SKYBLUE (-3125 5100);
FORCEPROP 1 LAST PACK_TYPE C0402
J 0
(-3125 4900);
DISPLAY 0.489362 (-3125 4900);
PAINT SKYBLUE (-3125 4900);
FORCEPROP 2 LAST CDS_LIB pure_quanta
J 0
(-3175 5100);
PAINT MONO (-3175 5100);
DISPLAY INVISIBLE (-3175 5100);
FORCEPROP 1 LAST PATH I157
J 0
(-3125 5250);
DISPLAY 0.978723 (-3125 5250);
PAINT WHITE (-3125 5250);
DISPLAY INVISIBLE (-3125 5250);
FORCEADD Q_CAP..1
(-4075 5900);
FORCEPROP 1 LAST LOCATION C2604
J 0
(-4025 6000);
DISPLAY 0.489362 (-4025 6000);
PAINT SKYBLUE (-4025 6000);
FORCEPROP 2 LAST $SEC 1
J 0
(-4025 6100);
DISPLAY 0.680851 (-4025 6100);
PAINT MONO (-4025 6100);
DISPLAY INVISIBLE (-4025 6100);
FORCEPROP 2 LAST CDS_SEC 1
J 0
(-4025 6100);
DISPLAY 1.021277 (-4025 6100);
DISPLAY INVISIBLE (-4025 6100);
FORCEPROP 1 LASTPIN (-4075 6000) $PN 1
J 0
(-4065 5980);
DISPLAY 0.489362 (-4065 5980);
FORCEPROP 1 LASTPIN (-4075 5800) $PN 2
J 0
(-4065 5780);
DISPLAY 0.489362 (-4065 5780);
FORCEPROP 1 LAST MATERIAL X6S
J 0
(-4025 5800);
DISPLAY 0.489362 (-4025 5800);
PAINT SKYBLUE (-4025 5800);
FORCEPROP 1 LAST TOLERANCE 20%
J 0
(-4025 5850);
DISPLAY 0.489362 (-4025 5850);
PAINT SKYBLUE (-4025 5850);
FORCEPROP 1 LAST VALUE 22UF
J 0
(-4025 5950);
DISPLAY 0.489362 (-4025 5950);
PAINT SKYBLUE (-4025 5950);
FORCEPROP 1 LAST PART_NUMBER CH622KMEB02
J 0
(-4025 5750);
DISPLAY 0.489362 (-4025 5750);
PAINT SKYBLUE (-4025 5750);
FORCEPROP 1 LAST VOLTAGE 4V
J 0
(-4025 5900);
DISPLAY 0.489362 (-4025 5900);
PAINT SKYBLUE (-4025 5900);
FORCEPROP 1 LAST PACK_TYPE C0402
J 0
(-4025 5700);
DISPLAY 0.489362 (-4025 5700);
PAINT SKYBLUE (-4025 5700);
FORCEPROP 2 LAST CDS_LIB pure_quanta
J 0
(-4075 5900);
PAINT MONO (-4075 5900);
DISPLAY INVISIBLE (-4075 5900);
FORCEPROP 1 LAST PATH I158
J 0
(-4025 6050);
DISPLAY 0.978723 (-4025 6050);
PAINT WHITE (-4025 6050);
DISPLAY INVISIBLE (-4025 6050);
FORCEADD Q_CAP..1
(-3625 5900);
FORCEPROP 1 LAST LOCATION C2611
J 0
(-3575 6000);
DISPLAY 0.489362 (-3575 6000);
PAINT SKYBLUE (-3575 6000);
FORCEPROP 2 LAST $SEC 1
J 0
(-3575 6100);
DISPLAY 0.680851 (-3575 6100);
PAINT MONO (-3575 6100);
DISPLAY INVISIBLE (-3575 6100);
FORCEPROP 2 LAST CDS_SEC 1
J 0
(-3575 6100);
DISPLAY 1.021277 (-3575 6100);
DISPLAY INVISIBLE (-3575 6100);
FORCEPROP 1 LASTPIN (-3625 6000) $PN 1
J 0
(-3615 5980);
DISPLAY 0.489362 (-3615 5980);
FORCEPROP 1 LASTPIN (-3625 5800) $PN 2
J 0
(-3615 5780);
DISPLAY 0.489362 (-3615 5780);
FORCEPROP 1 LAST MATERIAL X6S
J 0
(-3575 5800);
DISPLAY 0.489362 (-3575 5800);
PAINT SKYBLUE (-3575 5800);
FORCEPROP 1 LAST TOLERANCE 20%
J 0
(-3575 5850);
DISPLAY 0.489362 (-3575 5850);
PAINT SKYBLUE (-3575 5850);
FORCEPROP 1 LAST VALUE 22UF
J 0
(-3575 5950);
DISPLAY 0.489362 (-3575 5950);
PAINT SKYBLUE (-3575 5950);
FORCEPROP 1 LAST PART_NUMBER CH622KMEB02
J 0
(-3575 5750);
DISPLAY 0.489362 (-3575 5750);
PAINT SKYBLUE (-3575 5750);
FORCEPROP 1 LAST VOLTAGE 4V
J 0
(-3575 5900);
DISPLAY 0.489362 (-3575 5900);
PAINT SKYBLUE (-3575 5900);
FORCEPROP 1 LAST PACK_TYPE C0402
J 0
(-3575 5700);
DISPLAY 0.489362 (-3575 5700);
PAINT SKYBLUE (-3575 5700);
FORCEPROP 2 LAST CDS_LIB pure_quanta
J 0
(-3625 5900);
PAINT MONO (-3625 5900);
DISPLAY INVISIBLE (-3625 5900);
FORCEPROP 1 LAST PATH I159
J 0
(-3575 6050);
DISPLAY 0.978723 (-3575 6050);
PAINT WHITE (-3575 6050);
DISPLAY INVISIBLE (-3575 6050);
FORCEADD Q_CAP..1
(-9100 4425);
FORCEPROP 1 LAST LOCATION C2529
J 0
(-9050 4525);
DISPLAY 0.489362 (-9050 4525);
PAINT SKYBLUE (-9050 4525);
FORCEPROP 2 LAST $SEC 1
J 0
(-9050 4625);
DISPLAY 0.680851 (-9050 4625);
PAINT MONO (-9050 4625);
DISPLAY INVISIBLE (-9050 4625);
FORCEPROP 2 LAST CDS_SEC 1
J 0
(-9050 4625);
DISPLAY 1.021277 (-9050 4625);
DISPLAY INVISIBLE (-9050 4625);
FORCEPROP 1 LASTPIN (-9100 4525) $PN 1
J 0
(-9090 4505);
DISPLAY 0.489362 (-9090 4505);
FORCEPROP 1 LASTPIN (-9100 4325) $PN 2
J 0
(-9090 4305);
DISPLAY 0.489362 (-9090 4305);
FORCEPROP 1 LAST MATERIAL X6S
J 0
(-9050 4325);
DISPLAY 0.489362 (-9050 4325);
PAINT SKYBLUE (-9050 4325);
FORCEPROP 1 LAST TOLERANCE 20%
J 0
(-9050 4375);
DISPLAY 0.489362 (-9050 4375);
PAINT SKYBLUE (-9050 4375);
FORCEPROP 1 LAST VALUE 22UF
J 0
(-9050 4475);
DISPLAY 0.489362 (-9050 4475);
PAINT SKYBLUE (-9050 4475);
FORCEPROP 1 LAST PART_NUMBER CH622KMEB02
J 0
(-9050 4275);
DISPLAY 0.489362 (-9050 4275);
PAINT SKYBLUE (-9050 4275);
FORCEPROP 1 LAST VOLTAGE 4V
J 0
(-9050 4425);
DISPLAY 0.489362 (-9050 4425);
PAINT SKYBLUE (-9050 4425);
FORCEPROP 1 LAST PACK_TYPE C0402
J 0
(-9050 4225);
DISPLAY 0.489362 (-9050 4225);
PAINT SKYBLUE (-9050 4225);
FORCEPROP 2 LAST CDS_LIB pure_quanta
J 0
(-9100 4425);
PAINT MONO (-9100 4425);
DISPLAY INVISIBLE (-9100 4425);
FORCEPROP 1 LAST PATH I16
J 0
(-9050 4575);
DISPLAY 0.978723 (-9050 4575);
PAINT WHITE (-9050 4575);
DISPLAY INVISIBLE (-9050 4575);
FORCEADD Q_CAP..1
(-3175 5900);
FORCEPROP 1 LAST LOCATION C2618
J 0
(-3125 6000);
DISPLAY 0.489362 (-3125 6000);
PAINT SKYBLUE (-3125 6000);
FORCEPROP 2 LAST $SEC 1
J 0
(-3125 6100);
DISPLAY 0.680851 (-3125 6100);
PAINT MONO (-3125 6100);
DISPLAY INVISIBLE (-3125 6100);
FORCEPROP 2 LAST CDS_SEC 1
J 0
(-3125 6100);
DISPLAY 1.021277 (-3125 6100);
DISPLAY INVISIBLE (-3125 6100);
FORCEPROP 1 LASTPIN (-3175 6000) $PN 1
J 0
(-3165 5980);
DISPLAY 0.489362 (-3165 5980);
FORCEPROP 1 LASTPIN (-3175 5800) $PN 2
J 0
(-3165 5780);
DISPLAY 0.489362 (-3165 5780);
FORCEPROP 1 LAST MATERIAL X6S
J 0
(-3125 5800);
DISPLAY 0.489362 (-3125 5800);
PAINT SKYBLUE (-3125 5800);
FORCEPROP 1 LAST TOLERANCE 20%
J 0
(-3125 5850);
DISPLAY 0.489362 (-3125 5850);
PAINT SKYBLUE (-3125 5850);
FORCEPROP 1 LAST VALUE 22UF
J 0
(-3125 5950);
DISPLAY 0.489362 (-3125 5950);
PAINT SKYBLUE (-3125 5950);
FORCEPROP 1 LAST PART_NUMBER CH622KMEB02
J 0
(-3125 5750);
DISPLAY 0.489362 (-3125 5750);
PAINT SKYBLUE (-3125 5750);
FORCEPROP 1 LAST VOLTAGE 4V
J 0
(-3125 5900);
DISPLAY 0.489362 (-3125 5900);
PAINT SKYBLUE (-3125 5900);
FORCEPROP 1 LAST PACK_TYPE C0402
J 0
(-3125 5700);
DISPLAY 0.489362 (-3125 5700);
PAINT SKYBLUE (-3125 5700);
FORCEPROP 2 LAST CDS_LIB pure_quanta
J 0
(-3175 5900);
PAINT MONO (-3175 5900);
DISPLAY INVISIBLE (-3175 5900);
FORCEPROP 1 LAST PATH I160
J 0
(-3125 6050);
DISPLAY 0.978723 (-3125 6050);
PAINT WHITE (-3125 6050);
DISPLAY INVISIBLE (-3125 6050);
FORCEADD Q_CAP..1
(-3150 4325);
FORCEPROP 1 LAST LOCATION C2620
J 0
(-3100 4425);
DISPLAY 0.489362 (-3100 4425);
PAINT SKYBLUE (-3100 4425);
FORCEPROP 2 LAST $SEC 1
J 0
(-3100 4525);
DISPLAY 0.680851 (-3100 4525);
PAINT MONO (-3100 4525);
DISPLAY INVISIBLE (-3100 4525);
FORCEPROP 2 LAST CDS_SEC 1
J 0
(-3100 4525);
DISPLAY 1.021277 (-3100 4525);
DISPLAY INVISIBLE (-3100 4525);
FORCEPROP 1 LASTPIN (-3150 4425) $PN 1
J 0
(-3140 4405);
DISPLAY 0.489362 (-3140 4405);
FORCEPROP 1 LASTPIN (-3150 4225) $PN 2
J 0
(-3140 4205);
DISPLAY 0.489362 (-3140 4205);
FORCEPROP 1 LAST MATERIAL X6S
J 0
(-3100 4225);
DISPLAY 0.489362 (-3100 4225);
PAINT SKYBLUE (-3100 4225);
FORCEPROP 1 LAST TOLERANCE 20%
J 0
(-3100 4275);
DISPLAY 0.489362 (-3100 4275);
PAINT SKYBLUE (-3100 4275);
FORCEPROP 1 LAST VALUE 22UF
J 0
(-3100 4375);
DISPLAY 0.489362 (-3100 4375);
PAINT SKYBLUE (-3100 4375);
FORCEPROP 1 LAST PART_NUMBER CH622KMEB02
J 0
(-3100 4175);
DISPLAY 0.489362 (-3100 4175);
PAINT SKYBLUE (-3100 4175);
FORCEPROP 1 LAST VOLTAGE 4V
J 0
(-3100 4325);
DISPLAY 0.489362 (-3100 4325);
PAINT SKYBLUE (-3100 4325);
FORCEPROP 1 LAST PACK_TYPE C0402
J 0
(-3100 4125);
DISPLAY 0.489362 (-3100 4125);
PAINT SKYBLUE (-3100 4125);
FORCEPROP 2 LAST CDS_LIB pure_quanta
J 0
(-3150 4325);
PAINT MONO (-3150 4325);
DISPLAY INVISIBLE (-3150 4325);
FORCEPROP 1 LAST PATH I161
J 0
(-3100 4475);
DISPLAY 0.978723 (-3100 4475);
PAINT WHITE (-3100 4475);
DISPLAY INVISIBLE (-3100 4475);
FORCEADD Q_CAP..1
(-2725 5100);
FORCEPROP 1 LAST LOCATION C2626
J 0
(-2675 5200);
DISPLAY 0.489362 (-2675 5200);
PAINT SKYBLUE (-2675 5200);
FORCEPROP 2 LAST $SEC 1
J 0
(-2675 5300);
DISPLAY 0.680851 (-2675 5300);
PAINT MONO (-2675 5300);
DISPLAY INVISIBLE (-2675 5300);
FORCEPROP 2 LAST CDS_SEC 1
J 0
(-2675 5300);
DISPLAY 1.021277 (-2675 5300);
DISPLAY INVISIBLE (-2675 5300);
FORCEPROP 1 LASTPIN (-2725 5200) $PN 1
J 0
(-2715 5180);
DISPLAY 0.489362 (-2715 5180);
FORCEPROP 1 LASTPIN (-2725 5000) $PN 2
J 0
(-2715 4980);
DISPLAY 0.489362 (-2715 4980);
FORCEPROP 1 LAST MATERIAL X6S
J 0
(-2675 5000);
DISPLAY 0.489362 (-2675 5000);
PAINT SKYBLUE (-2675 5000);
FORCEPROP 1 LAST TOLERANCE 20%
J 0
(-2675 5050);
DISPLAY 0.489362 (-2675 5050);
PAINT SKYBLUE (-2675 5050);
FORCEPROP 1 LAST VALUE 22UF
J 0
(-2675 5150);
DISPLAY 0.489362 (-2675 5150);
PAINT SKYBLUE (-2675 5150);
FORCEPROP 1 LAST PART_NUMBER CH622KMEB02
J 0
(-2675 4950);
DISPLAY 0.489362 (-2675 4950);
PAINT SKYBLUE (-2675 4950);
FORCEPROP 1 LAST VOLTAGE 4V
J 0
(-2675 5100);
DISPLAY 0.489362 (-2675 5100);
PAINT SKYBLUE (-2675 5100);
FORCEPROP 1 LAST PACK_TYPE C0402
J 0
(-2675 4900);
DISPLAY 0.489362 (-2675 4900);
PAINT SKYBLUE (-2675 4900);
FORCEPROP 2 LAST CDS_LIB pure_quanta
J 0
(-2725 5100);
PAINT MONO (-2725 5100);
DISPLAY INVISIBLE (-2725 5100);
FORCEPROP 1 LAST PATH I162
J 0
(-2675 5250);
DISPLAY 0.978723 (-2675 5250);
PAINT WHITE (-2675 5250);
DISPLAY INVISIBLE (-2675 5250);
FORCEADD Q_CAP..1
(-2275 5100);
FORCEPROP 1 LAST LOCATION C2632
J 0
(-2225 5200);
DISPLAY 0.489362 (-2225 5200);
PAINT SKYBLUE (-2225 5200);
FORCEPROP 2 LAST $SEC 1
J 0
(-2225 5300);
DISPLAY 0.680851 (-2225 5300);
PAINT MONO (-2225 5300);
DISPLAY INVISIBLE (-2225 5300);
FORCEPROP 2 LAST CDS_SEC 1
J 0
(-2225 5300);
DISPLAY 1.021277 (-2225 5300);
DISPLAY INVISIBLE (-2225 5300);
FORCEPROP 1 LASTPIN (-2275 5200) $PN 1
J 0
(-2265 5180);
DISPLAY 0.489362 (-2265 5180);
FORCEPROP 1 LASTPIN (-2275 5000) $PN 2
J 0
(-2265 4980);
DISPLAY 0.489362 (-2265 4980);
FORCEPROP 1 LAST MATERIAL X6S
J 0
(-2225 5000);
DISPLAY 0.489362 (-2225 5000);
PAINT SKYBLUE (-2225 5000);
FORCEPROP 1 LAST TOLERANCE 20%
J 0
(-2225 5050);
DISPLAY 0.489362 (-2225 5050);
PAINT SKYBLUE (-2225 5050);
FORCEPROP 1 LAST VALUE 22UF
J 0
(-2225 5150);
DISPLAY 0.489362 (-2225 5150);
PAINT SKYBLUE (-2225 5150);
FORCEPROP 1 LAST PART_NUMBER CH622KMEB02
J 0
(-2225 4950);
DISPLAY 0.489362 (-2225 4950);
PAINT SKYBLUE (-2225 4950);
FORCEPROP 1 LAST VOLTAGE 4V
J 0
(-2225 5100);
DISPLAY 0.489362 (-2225 5100);
PAINT SKYBLUE (-2225 5100);
FORCEPROP 1 LAST PACK_TYPE C0402
J 0
(-2225 4900);
DISPLAY 0.489362 (-2225 4900);
PAINT SKYBLUE (-2225 4900);
FORCEPROP 2 LAST CDS_LIB pure_quanta
J 0
(-2275 5100);
PAINT MONO (-2275 5100);
DISPLAY INVISIBLE (-2275 5100);
FORCEPROP 1 LAST PATH I163
J 0
(-2225 5250);
DISPLAY 0.978723 (-2225 5250);
PAINT WHITE (-2225 5250);
DISPLAY INVISIBLE (-2225 5250);
FORCEADD Q_CAP..1
(-2725 5900);
FORCEPROP 1 LAST LOCATION C2625
J 0
(-2675 6000);
DISPLAY 0.489362 (-2675 6000);
PAINT SKYBLUE (-2675 6000);
FORCEPROP 2 LAST $SEC 1
J 0
(-2675 6100);
DISPLAY 0.680851 (-2675 6100);
PAINT MONO (-2675 6100);
DISPLAY INVISIBLE (-2675 6100);
FORCEPROP 2 LAST CDS_SEC 1
J 0
(-2675 6100);
DISPLAY 1.021277 (-2675 6100);
DISPLAY INVISIBLE (-2675 6100);
FORCEPROP 1 LASTPIN (-2725 6000) $PN 1
J 0
(-2715 5980);
DISPLAY 0.489362 (-2715 5980);
FORCEPROP 1 LASTPIN (-2725 5800) $PN 2
J 0
(-2715 5780);
DISPLAY 0.489362 (-2715 5780);
FORCEPROP 1 LAST MATERIAL X6S
J 0
(-2675 5800);
DISPLAY 0.489362 (-2675 5800);
PAINT SKYBLUE (-2675 5800);
FORCEPROP 1 LAST TOLERANCE 20%
J 0
(-2675 5850);
DISPLAY 0.489362 (-2675 5850);
PAINT SKYBLUE (-2675 5850);
FORCEPROP 1 LAST VALUE 22UF
J 0
(-2675 5950);
DISPLAY 0.489362 (-2675 5950);
PAINT SKYBLUE (-2675 5950);
FORCEPROP 1 LAST PART_NUMBER CH622KMEB02
J 0
(-2675 5750);
DISPLAY 0.489362 (-2675 5750);
PAINT SKYBLUE (-2675 5750);
FORCEPROP 1 LAST VOLTAGE 4V
J 0
(-2675 5900);
DISPLAY 0.489362 (-2675 5900);
PAINT SKYBLUE (-2675 5900);
FORCEPROP 1 LAST PACK_TYPE C0402
J 0
(-2675 5700);
DISPLAY 0.489362 (-2675 5700);
PAINT SKYBLUE (-2675 5700);
FORCEPROP 2 LAST CDS_LIB pure_quanta
J 0
(-2725 5900);
PAINT MONO (-2725 5900);
DISPLAY INVISIBLE (-2725 5900);
FORCEPROP 1 LAST PATH I164
J 0
(-2675 6050);
DISPLAY 0.978723 (-2675 6050);
PAINT WHITE (-2675 6050);
DISPLAY INVISIBLE (-2675 6050);
FORCEADD Q_CAP..1
(-2275 5900);
FORCEPROP 1 LAST LOCATION C2631
J 0
(-2225 6000);
DISPLAY 0.489362 (-2225 6000);
PAINT SKYBLUE (-2225 6000);
FORCEPROP 2 LAST $SEC 1
J 0
(-2225 6100);
DISPLAY 0.680851 (-2225 6100);
PAINT MONO (-2225 6100);
DISPLAY INVISIBLE (-2225 6100);
FORCEPROP 2 LAST CDS_SEC 1
J 0
(-2225 6100);
DISPLAY 1.021277 (-2225 6100);
DISPLAY INVISIBLE (-2225 6100);
FORCEPROP 1 LASTPIN (-2275 6000) $PN 1
J 0
(-2265 5980);
DISPLAY 0.489362 (-2265 5980);
FORCEPROP 1 LASTPIN (-2275 5800) $PN 2
J 0
(-2265 5780);
DISPLAY 0.489362 (-2265 5780);
FORCEPROP 1 LAST MATERIAL X6S
J 0
(-2225 5800);
DISPLAY 0.489362 (-2225 5800);
PAINT SKYBLUE (-2225 5800);
FORCEPROP 1 LAST TOLERANCE 20%
J 0
(-2225 5850);
DISPLAY 0.489362 (-2225 5850);
PAINT SKYBLUE (-2225 5850);
FORCEPROP 1 LAST VALUE 22UF
J 0
(-2225 5950);
DISPLAY 0.489362 (-2225 5950);
PAINT SKYBLUE (-2225 5950);
FORCEPROP 1 LAST PART_NUMBER CH622KMEB02
J 0
(-2225 5750);
DISPLAY 0.489362 (-2225 5750);
PAINT SKYBLUE (-2225 5750);
FORCEPROP 1 LAST VOLTAGE 4V
J 0
(-2225 5900);
DISPLAY 0.489362 (-2225 5900);
PAINT SKYBLUE (-2225 5900);
FORCEPROP 1 LAST PACK_TYPE C0402
J 0
(-2225 5700);
DISPLAY 0.489362 (-2225 5700);
PAINT SKYBLUE (-2225 5700);
FORCEPROP 2 LAST CDS_LIB pure_quanta
J 0
(-2275 5900);
PAINT MONO (-2275 5900);
DISPLAY INVISIBLE (-2275 5900);
FORCEPROP 1 LAST PATH I165
J 0
(-2225 6050);
DISPLAY 0.978723 (-2225 6050);
PAINT WHITE (-2225 6050);
DISPLAY INVISIBLE (-2225 6050);
FORCEADD Q_CAP..1
(-1825 5100);
FORCEPROP 1 LAST LOCATION C2638
J 0
(-1775 5200);
DISPLAY 0.489362 (-1775 5200);
PAINT SKYBLUE (-1775 5200);
FORCEPROP 2 LAST $SEC 1
J 0
(-1775 5300);
DISPLAY 0.680851 (-1775 5300);
PAINT MONO (-1775 5300);
DISPLAY INVISIBLE (-1775 5300);
FORCEPROP 2 LAST CDS_SEC 1
J 0
(-1775 5300);
DISPLAY 1.021277 (-1775 5300);
DISPLAY INVISIBLE (-1775 5300);
FORCEPROP 1 LASTPIN (-1825 5200) $PN 1
J 0
(-1815 5180);
DISPLAY 0.489362 (-1815 5180);
FORCEPROP 1 LASTPIN (-1825 5000) $PN 2
J 0
(-1815 4980);
DISPLAY 0.489362 (-1815 4980);
FORCEPROP 1 LAST MATERIAL X6S
J 0
(-1775 5000);
DISPLAY 0.489362 (-1775 5000);
PAINT SKYBLUE (-1775 5000);
FORCEPROP 1 LAST TOLERANCE 20%
J 0
(-1775 5050);
DISPLAY 0.489362 (-1775 5050);
PAINT SKYBLUE (-1775 5050);
FORCEPROP 1 LAST VALUE 22UF
J 0
(-1775 5150);
DISPLAY 0.489362 (-1775 5150);
PAINT SKYBLUE (-1775 5150);
FORCEPROP 1 LAST PART_NUMBER CH622KMEB02
J 0
(-1775 4950);
DISPLAY 0.489362 (-1775 4950);
PAINT SKYBLUE (-1775 4950);
FORCEPROP 1 LAST VOLTAGE 4V
J 0
(-1775 5100);
DISPLAY 0.489362 (-1775 5100);
PAINT SKYBLUE (-1775 5100);
FORCEPROP 1 LAST PACK_TYPE C0402
J 0
(-1775 4900);
DISPLAY 0.489362 (-1775 4900);
PAINT SKYBLUE (-1775 4900);
FORCEPROP 2 LAST CDS_LIB pure_quanta
J 0
(-1825 5100);
PAINT MONO (-1825 5100);
DISPLAY INVISIBLE (-1825 5100);
FORCEPROP 1 LAST PATH I166
J 0
(-1775 5250);
DISPLAY 0.978723 (-1775 5250);
PAINT WHITE (-1775 5250);
DISPLAY INVISIBLE (-1775 5250);
FORCEADD Q_CAP..1
(-1375 5100);
FORCEPROP 1 LAST LOCATION C2644
J 0
(-1325 5200);
DISPLAY 0.489362 (-1325 5200);
PAINT SKYBLUE (-1325 5200);
FORCEPROP 2 LAST $SEC 1
J 0
(-1325 5300);
DISPLAY 0.680851 (-1325 5300);
PAINT MONO (-1325 5300);
DISPLAY INVISIBLE (-1325 5300);
FORCEPROP 2 LAST CDS_SEC 1
J 0
(-1325 5300);
DISPLAY 1.021277 (-1325 5300);
DISPLAY INVISIBLE (-1325 5300);
FORCEPROP 1 LASTPIN (-1375 5200) $PN 1
J 0
(-1365 5180);
DISPLAY 0.489362 (-1365 5180);
FORCEPROP 1 LASTPIN (-1375 5000) $PN 2
J 0
(-1365 4980);
DISPLAY 0.489362 (-1365 4980);
FORCEPROP 1 LAST MATERIAL X6S
J 0
(-1325 5000);
DISPLAY 0.489362 (-1325 5000);
PAINT SKYBLUE (-1325 5000);
FORCEPROP 1 LAST TOLERANCE 20%
J 0
(-1325 5050);
DISPLAY 0.489362 (-1325 5050);
PAINT SKYBLUE (-1325 5050);
FORCEPROP 1 LAST VALUE 22UF
J 0
(-1325 5150);
DISPLAY 0.489362 (-1325 5150);
PAINT SKYBLUE (-1325 5150);
FORCEPROP 1 LAST PART_NUMBER CH622KMEB02
J 0
(-1325 4950);
DISPLAY 0.489362 (-1325 4950);
PAINT SKYBLUE (-1325 4950);
FORCEPROP 1 LAST VOLTAGE 4V
J 0
(-1325 5100);
DISPLAY 0.489362 (-1325 5100);
PAINT SKYBLUE (-1325 5100);
FORCEPROP 1 LAST PACK_TYPE C0402
J 0
(-1325 4900);
DISPLAY 0.489362 (-1325 4900);
PAINT SKYBLUE (-1325 4900);
FORCEPROP 2 LAST CDS_LIB pure_quanta
J 0
(-1375 5100);
PAINT MONO (-1375 5100);
DISPLAY INVISIBLE (-1375 5100);
FORCEPROP 1 LAST PATH I167
J 0
(-1325 5250);
DISPLAY 0.978723 (-1325 5250);
PAINT WHITE (-1325 5250);
DISPLAY INVISIBLE (-1325 5250);
FORCEADD Q_CAP..1
(-1825 5900);
FORCEPROP 1 LAST LOCATION C2637
J 0
(-1775 6000);
DISPLAY 0.489362 (-1775 6000);
PAINT SKYBLUE (-1775 6000);
FORCEPROP 2 LAST $SEC 1
J 0
(-1775 6100);
DISPLAY 0.680851 (-1775 6100);
PAINT MONO (-1775 6100);
DISPLAY INVISIBLE (-1775 6100);
FORCEPROP 2 LAST CDS_SEC 1
J 0
(-1775 6100);
DISPLAY 1.021277 (-1775 6100);
DISPLAY INVISIBLE (-1775 6100);
FORCEPROP 1 LASTPIN (-1825 6000) $PN 1
J 0
(-1815 5980);
DISPLAY 0.489362 (-1815 5980);
FORCEPROP 1 LASTPIN (-1825 5800) $PN 2
J 0
(-1815 5780);
DISPLAY 0.489362 (-1815 5780);
FORCEPROP 1 LAST MATERIAL X6S
J 0
(-1775 5800);
DISPLAY 0.489362 (-1775 5800);
PAINT SKYBLUE (-1775 5800);
FORCEPROP 1 LAST TOLERANCE 20%
J 0
(-1775 5850);
DISPLAY 0.489362 (-1775 5850);
PAINT SKYBLUE (-1775 5850);
FORCEPROP 1 LAST VALUE 22UF
J 0
(-1775 5950);
DISPLAY 0.489362 (-1775 5950);
PAINT SKYBLUE (-1775 5950);
FORCEPROP 1 LAST PART_NUMBER CH622KMEB02
J 0
(-1775 5750);
DISPLAY 0.489362 (-1775 5750);
PAINT SKYBLUE (-1775 5750);
FORCEPROP 1 LAST VOLTAGE 4V
J 0
(-1775 5900);
DISPLAY 0.489362 (-1775 5900);
PAINT SKYBLUE (-1775 5900);
FORCEPROP 1 LAST PACK_TYPE C0402
J 0
(-1775 5700);
DISPLAY 0.489362 (-1775 5700);
PAINT SKYBLUE (-1775 5700);
FORCEPROP 2 LAST CDS_LIB pure_quanta
J 0
(-1825 5900);
PAINT MONO (-1825 5900);
DISPLAY INVISIBLE (-1825 5900);
FORCEPROP 1 LAST PATH I168
J 0
(-1775 6050);
DISPLAY 0.978723 (-1775 6050);
PAINT WHITE (-1775 6050);
DISPLAY INVISIBLE (-1775 6050);
FORCEADD Q_CAP..1
(-1375 5900);
FORCEPROP 1 LAST LOCATION C2643
J 0
(-1325 6000);
DISPLAY 0.489362 (-1325 6000);
PAINT SKYBLUE (-1325 6000);
FORCEPROP 2 LAST $SEC 1
J 0
(-1325 6100);
DISPLAY 0.680851 (-1325 6100);
PAINT MONO (-1325 6100);
DISPLAY INVISIBLE (-1325 6100);
FORCEPROP 2 LAST CDS_SEC 1
J 0
(-1325 6100);
DISPLAY 1.021277 (-1325 6100);
DISPLAY INVISIBLE (-1325 6100);
FORCEPROP 1 LASTPIN (-1375 6000) $PN 1
J 0
(-1365 5980);
DISPLAY 0.489362 (-1365 5980);
FORCEPROP 1 LASTPIN (-1375 5800) $PN 2
J 0
(-1365 5780);
DISPLAY 0.489362 (-1365 5780);
FORCEPROP 1 LAST MATERIAL X6S
J 0
(-1325 5800);
DISPLAY 0.489362 (-1325 5800);
PAINT SKYBLUE (-1325 5800);
FORCEPROP 1 LAST TOLERANCE 20%
J 0
(-1325 5850);
DISPLAY 0.489362 (-1325 5850);
PAINT SKYBLUE (-1325 5850);
FORCEPROP 1 LAST VALUE 22UF
J 0
(-1325 5950);
DISPLAY 0.489362 (-1325 5950);
PAINT SKYBLUE (-1325 5950);
FORCEPROP 1 LAST PART_NUMBER CH622KMEB02
J 0
(-1325 5750);
DISPLAY 0.489362 (-1325 5750);
PAINT SKYBLUE (-1325 5750);
FORCEPROP 1 LAST VOLTAGE 4V
J 0
(-1325 5900);
DISPLAY 0.489362 (-1325 5900);
PAINT SKYBLUE (-1325 5900);
FORCEPROP 1 LAST PACK_TYPE C0402
J 0
(-1325 5700);
DISPLAY 0.489362 (-1325 5700);
PAINT SKYBLUE (-1325 5700);
FORCEPROP 2 LAST CDS_LIB pure_quanta
J 0
(-1375 5900);
PAINT MONO (-1375 5900);
DISPLAY INVISIBLE (-1375 5900);
FORCEPROP 1 LAST PATH I169
J 0
(-1325 6050);
DISPLAY 0.978723 (-1325 6050);
PAINT WHITE (-1325 6050);
DISPLAY INVISIBLE (-1325 6050);
FORCEADD UNIVERSAL_POWER..1
(-9100 4700);
FORCEPROP 3 LASTPIN (-9100 4650) SIG_NAME PVDDCR_SOC_P0\g
J 0
(-9090 4660);
DISPLAY 0.659574 (-9090 4660);
PAINT MONO (-9090 4660);
DISPLAY INVISIBLE (-9090 4660);
FORCEPROP 1 LAST HDL_POWER PVDDCR_SOC_P0
J 1
(-9100 4750);
DISPLAY 0.489362 (-9100 4750);
PAINT GREEN (-9100 4750);
FORCEPROP 2 LAST CDS_LIB pure_quanta_power
J 0
(-9100 4700);
DISPLAY INVISIBLE (-9100 4700);
FORCEPROP 1 LAST PATH I17
J 0
(-9050 4725);
DISPLAY 0.872340 (-9050 4725);
PAINT AQUA (-9050 4725);
DISPLAY INVISIBLE (-9050 4725);
FORCEADD Q_CAP..1
(-925 5100);
FORCEPROP 1 LAST LOCATION C2650
J 0
(-875 5200);
DISPLAY 0.489362 (-875 5200);
PAINT SKYBLUE (-875 5200);
FORCEPROP 2 LAST $SEC 1
J 0
(-875 5300);
DISPLAY 0.680851 (-875 5300);
PAINT MONO (-875 5300);
DISPLAY INVISIBLE (-875 5300);
FORCEPROP 2 LAST CDS_SEC 1
J 0
(-875 5300);
DISPLAY 1.021277 (-875 5300);
DISPLAY INVISIBLE (-875 5300);
FORCEPROP 1 LASTPIN (-925 5200) $PN 1
J 0
(-915 5180);
DISPLAY 0.489362 (-915 5180);
FORCEPROP 1 LASTPIN (-925 5000) $PN 2
J 0
(-915 4980);
DISPLAY 0.489362 (-915 4980);
FORCEPROP 1 LAST MATERIAL X6S
J 0
(-875 5000);
DISPLAY 0.489362 (-875 5000);
PAINT SKYBLUE (-875 5000);
FORCEPROP 1 LAST TOLERANCE 20%
J 0
(-875 5050);
DISPLAY 0.489362 (-875 5050);
PAINT SKYBLUE (-875 5050);
FORCEPROP 1 LAST VALUE 22UF
J 0
(-875 5150);
DISPLAY 0.489362 (-875 5150);
PAINT SKYBLUE (-875 5150);
FORCEPROP 1 LAST PART_NUMBER CH622KMEB02
J 0
(-875 4950);
DISPLAY 0.489362 (-875 4950);
PAINT SKYBLUE (-875 4950);
FORCEPROP 1 LAST VOLTAGE 4V
J 0
(-875 5100);
DISPLAY 0.489362 (-875 5100);
PAINT SKYBLUE (-875 5100);
FORCEPROP 1 LAST PACK_TYPE C0402
J 0
(-875 4900);
DISPLAY 0.489362 (-875 4900);
PAINT SKYBLUE (-875 4900);
FORCEPROP 2 LAST CDS_LIB pure_quanta
J 0
(-925 5100);
PAINT MONO (-925 5100);
DISPLAY INVISIBLE (-925 5100);
FORCEPROP 1 LAST PATH I170
J 0
(-875 5250);
DISPLAY 0.978723 (-875 5250);
PAINT WHITE (-875 5250);
DISPLAY INVISIBLE (-875 5250);
FORCEADD UNIVERSAL_GND..1
(-525 4725);
FORCEPROP 3 LASTPIN (-525 4775) SIG_NAME GND\g
J 0
(-515 4785);
DISPLAY 0.659574 (-515 4785);
PAINT MONO (-515 4785);
DISPLAY INVISIBLE (-515 4785);
FORCEPROP 2 LAST CDS_LIB pure_quanta_power
J 0
(-525 4725);
PAINT MONO (-525 4725);
DISPLAY INVISIBLE (-525 4725);
FORCEPROP 1 LAST PATH I171
J 0
(-450 4725);
DISPLAY 0.872340 (-450 4725);
PAINT AQUA (-450 4725);
DISPLAY INVISIBLE (-450 4725);
FORCEPROP 1 LAST HDL_POWER GND
J 1
(-500 4650);
DISPLAY 0.872340 (-500 4650);
PAINT GREEN (-500 4650);
DISPLAY INVISIBLE (-500 4650);
FORCEADD Q_CAP..1
(-525 5100);
FORCEPROP 1 LAST LOCATION C2655
J 0
(-475 5200);
DISPLAY 0.489362 (-475 5200);
PAINT SKYBLUE (-475 5200);
FORCEPROP 2 LAST $SEC 1
J 0
(-475 5300);
DISPLAY 0.680851 (-475 5300);
PAINT MONO (-475 5300);
DISPLAY INVISIBLE (-475 5300);
FORCEPROP 2 LAST CDS_SEC 1
J 0
(-475 5300);
DISPLAY 1.021277 (-475 5300);
DISPLAY INVISIBLE (-475 5300);
FORCEPROP 1 LASTPIN (-525 5200) $PN 1
J 0
(-515 5180);
DISPLAY 0.489362 (-515 5180);
FORCEPROP 1 LASTPIN (-525 5000) $PN 2
J 0
(-515 4980);
DISPLAY 0.489362 (-515 4980);
FORCEPROP 1 LAST MATERIAL X6S
J 0
(-475 5000);
DISPLAY 0.489362 (-475 5000);
PAINT SKYBLUE (-475 5000);
FORCEPROP 1 LAST TOLERANCE 20%
J 0
(-475 5050);
DISPLAY 0.489362 (-475 5050);
PAINT SKYBLUE (-475 5050);
FORCEPROP 1 LAST VALUE 22UF
J 0
(-475 5150);
DISPLAY 0.489362 (-475 5150);
PAINT SKYBLUE (-475 5150);
FORCEPROP 1 LAST PART_NUMBER CH622KMEB02
J 0
(-475 4950);
DISPLAY 0.489362 (-475 4950);
PAINT SKYBLUE (-475 4950);
FORCEPROP 1 LAST VOLTAGE 4V
J 0
(-475 5100);
DISPLAY 0.489362 (-475 5100);
PAINT SKYBLUE (-475 5100);
FORCEPROP 1 LAST PACK_TYPE C0402
J 0
(-475 4900);
DISPLAY 0.489362 (-475 4900);
PAINT SKYBLUE (-475 4900);
FORCEPROP 2 LAST CDS_LIB pure_quanta
J 0
(-525 5100);
PAINT MONO (-525 5100);
DISPLAY INVISIBLE (-525 5100);
FORCEPROP 1 LAST PATH I172
J 0
(-475 5250);
DISPLAY 0.978723 (-475 5250);
PAINT WHITE (-475 5250);
DISPLAY INVISIBLE (-475 5250);
FORCEADD Q_CAP..1
(-925 5900);
FORCEPROP 1 LAST LOCATION C2649
J 0
(-875 6000);
DISPLAY 0.489362 (-875 6000);
PAINT SKYBLUE (-875 6000);
FORCEPROP 2 LAST $SEC 1
J 0
(-875 6100);
DISPLAY 0.680851 (-875 6100);
PAINT MONO (-875 6100);
DISPLAY INVISIBLE (-875 6100);
FORCEPROP 2 LAST CDS_SEC 1
J 0
(-875 6100);
DISPLAY 1.021277 (-875 6100);
DISPLAY INVISIBLE (-875 6100);
FORCEPROP 1 LASTPIN (-925 6000) $PN 1
J 0
(-915 5980);
DISPLAY 0.489362 (-915 5980);
FORCEPROP 1 LASTPIN (-925 5800) $PN 2
J 0
(-915 5780);
DISPLAY 0.489362 (-915 5780);
FORCEPROP 1 LAST MATERIAL X6S
J 0
(-875 5800);
DISPLAY 0.489362 (-875 5800);
PAINT SKYBLUE (-875 5800);
FORCEPROP 1 LAST TOLERANCE 20%
J 0
(-875 5850);
DISPLAY 0.489362 (-875 5850);
PAINT SKYBLUE (-875 5850);
FORCEPROP 1 LAST VALUE 22UF
J 0
(-875 5950);
DISPLAY 0.489362 (-875 5950);
PAINT SKYBLUE (-875 5950);
FORCEPROP 1 LAST PART_NUMBER CH622KMEB02
J 0
(-875 5750);
DISPLAY 0.489362 (-875 5750);
PAINT SKYBLUE (-875 5750);
FORCEPROP 1 LAST VOLTAGE 4V
J 0
(-875 5900);
DISPLAY 0.489362 (-875 5900);
PAINT SKYBLUE (-875 5900);
FORCEPROP 1 LAST PACK_TYPE C0402
J 0
(-875 5700);
DISPLAY 0.489362 (-875 5700);
PAINT SKYBLUE (-875 5700);
FORCEPROP 2 LAST CDS_LIB pure_quanta
J 0
(-925 5900);
PAINT MONO (-925 5900);
DISPLAY INVISIBLE (-925 5900);
FORCEPROP 1 LAST PATH I173
J 0
(-875 6050);
DISPLAY 0.978723 (-875 6050);
PAINT WHITE (-875 6050);
DISPLAY INVISIBLE (-875 6050);
FORCEADD UNIVERSAL_GND..1
(-525 5525);
FORCEPROP 3 LASTPIN (-525 5575) SIG_NAME GND\g
J 0
(-515 5585);
DISPLAY 0.659574 (-515 5585);
PAINT MONO (-515 5585);
DISPLAY INVISIBLE (-515 5585);
FORCEPROP 2 LAST CDS_LIB pure_quanta_power
J 0
(-525 5525);
PAINT MONO (-525 5525);
DISPLAY INVISIBLE (-525 5525);
FORCEPROP 1 LAST PATH I174
J 0
(-450 5525);
DISPLAY 0.872340 (-450 5525);
PAINT AQUA (-450 5525);
DISPLAY INVISIBLE (-450 5525);
FORCEPROP 1 LAST HDL_POWER GND
J 1
(-500 5450);
DISPLAY 0.872340 (-500 5450);
PAINT GREEN (-500 5450);
DISPLAY INVISIBLE (-500 5450);
FORCEADD Q_CAP..1
(-525 5900);
FORCEPROP 1 LAST LOCATION C2654
J 0
(-475 6000);
DISPLAY 0.489362 (-475 6000);
PAINT SKYBLUE (-475 6000);
FORCEPROP 2 LAST $SEC 1
J 0
(-475 6100);
DISPLAY 0.680851 (-475 6100);
PAINT MONO (-475 6100);
DISPLAY INVISIBLE (-475 6100);
FORCEPROP 2 LAST CDS_SEC 1
J 0
(-475 6100);
DISPLAY 1.021277 (-475 6100);
DISPLAY INVISIBLE (-475 6100);
FORCEPROP 1 LASTPIN (-525 6000) $PN 1
J 0
(-515 5980);
DISPLAY 0.489362 (-515 5980);
FORCEPROP 1 LASTPIN (-525 5800) $PN 2
J 0
(-515 5780);
DISPLAY 0.489362 (-515 5780);
FORCEPROP 1 LAST MATERIAL X6S
J 0
(-475 5800);
DISPLAY 0.489362 (-475 5800);
PAINT SKYBLUE (-475 5800);
FORCEPROP 1 LAST TOLERANCE 20%
J 0
(-475 5850);
DISPLAY 0.489362 (-475 5850);
PAINT SKYBLUE (-475 5850);
FORCEPROP 1 LAST VALUE 22UF
J 0
(-475 5950);
DISPLAY 0.489362 (-475 5950);
PAINT SKYBLUE (-475 5950);
FORCEPROP 1 LAST PART_NUMBER CH622KMEB02
J 0
(-475 5750);
DISPLAY 0.489362 (-475 5750);
PAINT SKYBLUE (-475 5750);
FORCEPROP 1 LAST VOLTAGE 4V
J 0
(-475 5900);
DISPLAY 0.489362 (-475 5900);
PAINT SKYBLUE (-475 5900);
FORCEPROP 1 LAST PACK_TYPE C0402
J 0
(-475 5700);
DISPLAY 0.489362 (-475 5700);
PAINT SKYBLUE (-475 5700);
FORCEPROP 2 LAST CDS_LIB pure_quanta
J 0
(-525 5900);
PAINT MONO (-525 5900);
DISPLAY INVISIBLE (-525 5900);
FORCEPROP 1 LAST PATH I175
J 0
(-475 6050);
DISPLAY 0.978723 (-475 6050);
PAINT WHITE (-475 6050);
DISPLAY INVISIBLE (-475 6050);
FORCEADD Q_CAP..1
(-9100 5150);
FORCEPROP 1 LAST LOCATION C2528
J 0
(-9050 5250);
DISPLAY 0.489362 (-9050 5250);
PAINT SKYBLUE (-9050 5250);
FORCEPROP 2 LAST $SEC 1
J 0
(-9050 5350);
DISPLAY 0.680851 (-9050 5350);
PAINT MONO (-9050 5350);
DISPLAY INVISIBLE (-9050 5350);
FORCEPROP 2 LAST CDS_SEC 1
J 0
(-9050 5350);
DISPLAY 1.021277 (-9050 5350);
DISPLAY INVISIBLE (-9050 5350);
FORCEPROP 1 LASTPIN (-9100 5250) $PN 1
J 0
(-9090 5230);
DISPLAY 0.489362 (-9090 5230);
FORCEPROP 1 LASTPIN (-9100 5050) $PN 2
J 0
(-9090 5030);
DISPLAY 0.489362 (-9090 5030);
FORCEPROP 1 LAST MATERIAL X6S
J 0
(-9050 5050);
DISPLAY 0.489362 (-9050 5050);
PAINT SKYBLUE (-9050 5050);
FORCEPROP 1 LAST TOLERANCE 20%
J 0
(-9050 5100);
DISPLAY 0.489362 (-9050 5100);
PAINT SKYBLUE (-9050 5100);
FORCEPROP 1 LAST VALUE 22UF
J 0
(-9050 5200);
DISPLAY 0.489362 (-9050 5200);
PAINT SKYBLUE (-9050 5200);
FORCEPROP 1 LAST PART_NUMBER CH622KMEB02
J 0
(-9050 5000);
DISPLAY 0.489362 (-9050 5000);
PAINT SKYBLUE (-9050 5000);
FORCEPROP 1 LAST VOLTAGE 4V
J 0
(-9050 5150);
DISPLAY 0.489362 (-9050 5150);
PAINT SKYBLUE (-9050 5150);
FORCEPROP 1 LAST PACK_TYPE C0402
J 0
(-9050 4950);
DISPLAY 0.489362 (-9050 4950);
PAINT SKYBLUE (-9050 4950);
FORCEPROP 2 LAST CDS_LIB pure_quanta
J 0
(-9100 5150);
PAINT MONO (-9100 5150);
DISPLAY INVISIBLE (-9100 5150);
FORCEPROP 1 LAST PATH I18
J 0
(-9050 5300);
DISPLAY 0.978723 (-9050 5300);
PAINT WHITE (-9050 5300);
DISPLAY INVISIBLE (-9050 5300);
FORCEADD Q_CAP..1
(-8650 4425);
FORCEPROP 1 LAST LOCATION C2536
J 0
(-8600 4525);
DISPLAY 0.489362 (-8600 4525);
PAINT SKYBLUE (-8600 4525);
FORCEPROP 2 LAST $SEC 1
J 0
(-8600 4625);
DISPLAY 0.680851 (-8600 4625);
PAINT MONO (-8600 4625);
DISPLAY INVISIBLE (-8600 4625);
FORCEPROP 2 LAST CDS_SEC 1
J 0
(-8600 4625);
DISPLAY 1.021277 (-8600 4625);
DISPLAY INVISIBLE (-8600 4625);
FORCEPROP 1 LASTPIN (-8650 4525) $PN 1
J 0
(-8640 4505);
DISPLAY 0.489362 (-8640 4505);
FORCEPROP 1 LASTPIN (-8650 4325) $PN 2
J 0
(-8640 4305);
DISPLAY 0.489362 (-8640 4305);
FORCEPROP 1 LAST MATERIAL X6S
J 0
(-8600 4325);
DISPLAY 0.489362 (-8600 4325);
PAINT SKYBLUE (-8600 4325);
FORCEPROP 1 LAST TOLERANCE 20%
J 0
(-8600 4375);
DISPLAY 0.489362 (-8600 4375);
PAINT SKYBLUE (-8600 4375);
FORCEPROP 1 LAST VALUE 22UF
J 0
(-8600 4475);
DISPLAY 0.489362 (-8600 4475);
PAINT SKYBLUE (-8600 4475);
FORCEPROP 1 LAST PART_NUMBER CH622KMEB02
J 0
(-8600 4275);
DISPLAY 0.489362 (-8600 4275);
PAINT SKYBLUE (-8600 4275);
FORCEPROP 1 LAST VOLTAGE 4V
J 0
(-8600 4425);
DISPLAY 0.489362 (-8600 4425);
PAINT SKYBLUE (-8600 4425);
FORCEPROP 1 LAST PACK_TYPE C0402
J 0
(-8600 4225);
DISPLAY 0.489362 (-8600 4225);
PAINT SKYBLUE (-8600 4225);
FORCEPROP 2 LAST CDS_LIB pure_quanta
J 0
(-8650 4425);
PAINT MONO (-8650 4425);
DISPLAY INVISIBLE (-8650 4425);
FORCEPROP 1 LAST PATH I19
J 0
(-8600 4575);
DISPLAY 0.978723 (-8600 4575);
PAINT WHITE (-8600 4575);
DISPLAY INVISIBLE (-8600 4575);
FORCEADD UNIVERSAL_POWER..1
(-9075 1150);
FORCEPROP 3 LASTPIN (-9075 1100) SIG_NAME PVDDCR_SOC_P0\g
J 0
(-9065 1110);
DISPLAY 0.659574 (-9065 1110);
PAINT MONO (-9065 1110);
DISPLAY INVISIBLE (-9065 1110);
FORCEPROP 1 LAST HDL_POWER PVDDCR_SOC_P0
J 1
(-9075 1200);
DISPLAY 0.489362 (-9075 1200);
PAINT GREEN (-9075 1200);
FORCEPROP 2 LAST CDS_LIB pure_quanta_power
J 0
(-9075 1150);
DISPLAY INVISIBLE (-9075 1150);
FORCEPROP 1 LAST PATH I2
J 0
(-9025 1175);
DISPLAY 0.872340 (-9025 1175);
PAINT AQUA (-9025 1175);
DISPLAY INVISIBLE (-9025 1175);
FORCEADD Q_CAP..1
(-8650 5150);
FORCEPROP 1 LAST LOCATION C2535
J 0
(-8600 5250);
DISPLAY 0.489362 (-8600 5250);
PAINT SKYBLUE (-8600 5250);
FORCEPROP 2 LAST $SEC 1
J 0
(-8600 5350);
DISPLAY 0.680851 (-8600 5350);
PAINT MONO (-8600 5350);
DISPLAY INVISIBLE (-8600 5350);
FORCEPROP 2 LAST CDS_SEC 1
J 0
(-8600 5350);
DISPLAY 1.021277 (-8600 5350);
DISPLAY INVISIBLE (-8600 5350);
FORCEPROP 1 LASTPIN (-8650 5250) $PN 1
J 0
(-8640 5230);
DISPLAY 0.489362 (-8640 5230);
FORCEPROP 1 LASTPIN (-8650 5050) $PN 2
J 0
(-8640 5030);
DISPLAY 0.489362 (-8640 5030);
FORCEPROP 1 LAST MATERIAL X6S
J 0
(-8600 5050);
DISPLAY 0.489362 (-8600 5050);
PAINT SKYBLUE (-8600 5050);
FORCEPROP 1 LAST TOLERANCE 20%
J 0
(-8600 5100);
DISPLAY 0.489362 (-8600 5100);
PAINT SKYBLUE (-8600 5100);
FORCEPROP 1 LAST VALUE 22UF
J 0
(-8600 5200);
DISPLAY 0.489362 (-8600 5200);
PAINT SKYBLUE (-8600 5200);
FORCEPROP 1 LAST PART_NUMBER CH622KMEB02
J 0
(-8600 5000);
DISPLAY 0.489362 (-8600 5000);
PAINT SKYBLUE (-8600 5000);
FORCEPROP 1 LAST VOLTAGE 4V
J 0
(-8600 5150);
DISPLAY 0.489362 (-8600 5150);
PAINT SKYBLUE (-8600 5150);
FORCEPROP 1 LAST PACK_TYPE C0402
J 0
(-8600 4950);
DISPLAY 0.489362 (-8600 4950);
PAINT SKYBLUE (-8600 4950);
FORCEPROP 2 LAST CDS_LIB pure_quanta
J 0
(-8650 5150);
PAINT MONO (-8650 5150);
DISPLAY INVISIBLE (-8650 5150);
FORCEPROP 1 LAST PATH I20
J 0
(-8600 5300);
DISPLAY 0.978723 (-8600 5300);
PAINT WHITE (-8600 5300);
DISPLAY INVISIBLE (-8600 5300);
FORCEADD UNIVERSAL_POWER..1
(-9100 5425);
FORCEPROP 3 LASTPIN (-9100 5375) SIG_NAME PVDDCR_SOC_P0\g
J 0
(-9090 5385);
DISPLAY 0.659574 (-9090 5385);
PAINT MONO (-9090 5385);
DISPLAY INVISIBLE (-9090 5385);
FORCEPROP 1 LAST HDL_POWER PVDDCR_SOC_P0
J 1
(-9100 5475);
DISPLAY 0.489362 (-9100 5475);
PAINT GREEN (-9100 5475);
FORCEPROP 2 LAST CDS_LIB pure_quanta_power
J 0
(-9100 5425);
DISPLAY INVISIBLE (-9100 5425);
FORCEPROP 1 LAST PATH I21
J 0
(-9050 5450);
DISPLAY 0.872340 (-9050 5450);
PAINT AQUA (-9050 5450);
DISPLAY INVISIBLE (-9050 5450);
FORCEADD Q_CAP..1
(-9100 5900);
FORCEPROP 1 LAST LOCATION C2527
J 0
(-9050 6000);
DISPLAY 0.489362 (-9050 6000);
PAINT SKYBLUE (-9050 6000);
FORCEPROP 2 LAST $SEC 1
J 0
(-9050 6100);
DISPLAY 0.680851 (-9050 6100);
PAINT MONO (-9050 6100);
DISPLAY INVISIBLE (-9050 6100);
FORCEPROP 2 LAST CDS_SEC 1
J 0
(-9050 6100);
DISPLAY 1.021277 (-9050 6100);
DISPLAY INVISIBLE (-9050 6100);
FORCEPROP 1 LASTPIN (-9100 6000) $PN 1
J 0
(-9090 5980);
DISPLAY 0.489362 (-9090 5980);
FORCEPROP 1 LASTPIN (-9100 5800) $PN 2
J 0
(-9090 5780);
DISPLAY 0.489362 (-9090 5780);
FORCEPROP 1 LAST MATERIAL X6S
J 0
(-9050 5800);
DISPLAY 0.489362 (-9050 5800);
PAINT SKYBLUE (-9050 5800);
FORCEPROP 1 LAST TOLERANCE 20%
J 0
(-9050 5850);
DISPLAY 0.489362 (-9050 5850);
PAINT SKYBLUE (-9050 5850);
FORCEPROP 1 LAST VALUE 22UF
J 0
(-9050 5950);
DISPLAY 0.489362 (-9050 5950);
PAINT SKYBLUE (-9050 5950);
FORCEPROP 1 LAST PART_NUMBER CH622KMEB02
J 0
(-9050 5750);
DISPLAY 0.489362 (-9050 5750);
PAINT SKYBLUE (-9050 5750);
FORCEPROP 1 LAST VOLTAGE 4V
J 0
(-9050 5900);
DISPLAY 0.489362 (-9050 5900);
PAINT SKYBLUE (-9050 5900);
FORCEPROP 1 LAST PACK_TYPE C0402
J 0
(-9050 5700);
DISPLAY 0.489362 (-9050 5700);
PAINT SKYBLUE (-9050 5700);
FORCEPROP 2 LAST CDS_LIB pure_quanta
J 0
(-9100 5900);
PAINT MONO (-9100 5900);
DISPLAY INVISIBLE (-9100 5900);
FORCEPROP 1 LAST PATH I22
J 0
(-9050 6050);
DISPLAY 0.978723 (-9050 6050);
PAINT WHITE (-9050 6050);
DISPLAY INVISIBLE (-9050 6050);
FORCEADD UNIVERSAL_POWER..1
(-9100 6175);
FORCEPROP 3 LASTPIN (-9100 6125) SIG_NAME PVDDCR_SOC_P0\g
J 0
(-9090 6135);
DISPLAY 0.659574 (-9090 6135);
PAINT MONO (-9090 6135);
DISPLAY INVISIBLE (-9090 6135);
FORCEPROP 1 LAST HDL_POWER PVDDCR_SOC_P0
J 1
(-9100 6225);
DISPLAY 0.489362 (-9100 6225);
PAINT GREEN (-9100 6225);
FORCEPROP 2 LAST CDS_LIB pure_quanta_power
J 0
(-9100 6175);
DISPLAY INVISIBLE (-9100 6175);
FORCEPROP 1 LAST PATH I23
J 0
(-9050 6200);
DISPLAY 0.872340 (-9050 6200);
PAINT AQUA (-9050 6200);
DISPLAY INVISIBLE (-9050 6200);
FORCEADD Q_CAP..1
(-8650 5900);
FORCEPROP 1 LAST LOCATION C2534
J 0
(-8600 6000);
DISPLAY 0.489362 (-8600 6000);
PAINT SKYBLUE (-8600 6000);
FORCEPROP 2 LAST $SEC 1
J 0
(-8600 6100);
DISPLAY 0.680851 (-8600 6100);
PAINT MONO (-8600 6100);
DISPLAY INVISIBLE (-8600 6100);
FORCEPROP 2 LAST CDS_SEC 1
J 0
(-8600 6100);
DISPLAY 1.021277 (-8600 6100);
DISPLAY INVISIBLE (-8600 6100);
FORCEPROP 1 LASTPIN (-8650 6000) $PN 1
J 0
(-8640 5980);
DISPLAY 0.489362 (-8640 5980);
FORCEPROP 1 LASTPIN (-8650 5800) $PN 2
J 0
(-8640 5780);
DISPLAY 0.489362 (-8640 5780);
FORCEPROP 1 LAST MATERIAL X6S
J 0
(-8600 5800);
DISPLAY 0.489362 (-8600 5800);
PAINT SKYBLUE (-8600 5800);
FORCEPROP 1 LAST TOLERANCE 20%
J 0
(-8600 5850);
DISPLAY 0.489362 (-8600 5850);
PAINT SKYBLUE (-8600 5850);
FORCEPROP 1 LAST VALUE 22UF
J 0
(-8600 5950);
DISPLAY 0.489362 (-8600 5950);
PAINT SKYBLUE (-8600 5950);
FORCEPROP 1 LAST PART_NUMBER CH622KMEB02
J 0
(-8600 5750);
DISPLAY 0.489362 (-8600 5750);
PAINT SKYBLUE (-8600 5750);
FORCEPROP 1 LAST VOLTAGE 4V
J 0
(-8600 5900);
DISPLAY 0.489362 (-8600 5900);
PAINT SKYBLUE (-8600 5900);
FORCEPROP 1 LAST PACK_TYPE C0402
J 0
(-8600 5700);
DISPLAY 0.489362 (-8600 5700);
PAINT SKYBLUE (-8600 5700);
FORCEPROP 2 LAST CDS_LIB pure_quanta
J 0
(-8650 5900);
PAINT MONO (-8650 5900);
DISPLAY INVISIBLE (-8650 5900);
FORCEPROP 1 LAST PATH I24
J 0
(-8600 6050);
DISPLAY 0.978723 (-8600 6050);
PAINT WHITE (-8600 6050);
DISPLAY INVISIBLE (-8600 6050);
FORCEADD Q_CAP..1
(-8175 875);
FORCEPROP 1 LAST LOCATION C3927
J 0
(-8125 975);
DISPLAY 0.489362 (-8125 975);
PAINT SKYBLUE (-8125 975);
FORCEPROP 2 LAST $SEC 1
J 0
(-8125 1075);
DISPLAY 0.680851 (-8125 1075);
PAINT MONO (-8125 1075);
DISPLAY INVISIBLE (-8125 1075);
FORCEPROP 2 LAST CDS_SEC 1
J 0
(-8125 1075);
DISPLAY 1.021277 (-8125 1075);
DISPLAY INVISIBLE (-8125 1075);
FORCEPROP 1 LASTPIN (-8175 975) $PN 1
J 0
(-8165 955);
DISPLAY 0.489362 (-8165 955);
FORCEPROP 1 LASTPIN (-8175 775) $PN 2
J 0
(-8165 755);
DISPLAY 0.489362 (-8165 755);
FORCEPROP 1 LAST MATERIAL X6S
J 0
(-8125 775);
DISPLAY 0.489362 (-8125 775);
PAINT SKYBLUE (-8125 775);
FORCEPROP 1 LAST TOLERANCE 20%
J 0
(-8125 825);
DISPLAY 0.489362 (-8125 825);
PAINT SKYBLUE (-8125 825);
FORCEPROP 1 LAST VALUE 22UF
J 0
(-8125 925);
DISPLAY 0.489362 (-8125 925);
PAINT SKYBLUE (-8125 925);
FORCEPROP 1 LAST PART_NUMBER CH622KMEB02
J 0
(-8125 725);
DISPLAY 0.489362 (-8125 725);
PAINT SKYBLUE (-8125 725);
FORCEPROP 1 LAST VOLTAGE 4V
J 0
(-8125 875);
DISPLAY 0.489362 (-8125 875);
PAINT SKYBLUE (-8125 875);
FORCEPROP 1 LAST PACK_TYPE C0402
J 0
(-8125 675);
DISPLAY 0.489362 (-8125 675);
PAINT SKYBLUE (-8125 675);
FORCEPROP 2 LAST CDS_LIB pure_quanta
J 0
(-8175 875);
PAINT MONO (-8175 875);
DISPLAY INVISIBLE (-8175 875);
FORCEPROP 1 LAST PATH I25
J 0
(-8125 1025);
DISPLAY 0.978723 (-8125 1025);
PAINT WHITE (-8125 1025);
DISPLAY INVISIBLE (-8125 1025);
FORCEADD Q_CAP..1
(-7725 875);
FORCEPROP 1 LAST LOCATION C3928
J 0
(-7675 975);
DISPLAY 0.489362 (-7675 975);
PAINT SKYBLUE (-7675 975);
FORCEPROP 2 LAST $SEC 1
J 0
(-7675 1075);
DISPLAY 0.680851 (-7675 1075);
PAINT MONO (-7675 1075);
DISPLAY INVISIBLE (-7675 1075);
FORCEPROP 2 LAST CDS_SEC 1
J 0
(-7675 1075);
DISPLAY 1.021277 (-7675 1075);
DISPLAY INVISIBLE (-7675 1075);
FORCEPROP 1 LASTPIN (-7725 975) $PN 1
J 0
(-7715 955);
DISPLAY 0.489362 (-7715 955);
FORCEPROP 1 LASTPIN (-7725 775) $PN 2
J 0
(-7715 755);
DISPLAY 0.489362 (-7715 755);
FORCEPROP 1 LAST MATERIAL X6S
J 0
(-7675 775);
DISPLAY 0.489362 (-7675 775);
PAINT SKYBLUE (-7675 775);
FORCEPROP 1 LAST TOLERANCE 20%
J 0
(-7675 825);
DISPLAY 0.489362 (-7675 825);
PAINT SKYBLUE (-7675 825);
FORCEPROP 1 LAST VALUE 22UF
J 0
(-7675 925);
DISPLAY 0.489362 (-7675 925);
PAINT SKYBLUE (-7675 925);
FORCEPROP 1 LAST PART_NUMBER CH622KMEB02
J 0
(-7675 725);
DISPLAY 0.489362 (-7675 725);
PAINT SKYBLUE (-7675 725);
FORCEPROP 1 LAST VOLTAGE 4V
J 0
(-7675 875);
DISPLAY 0.489362 (-7675 875);
PAINT SKYBLUE (-7675 875);
FORCEPROP 1 LAST PACK_TYPE C0402
J 0
(-7675 675);
DISPLAY 0.489362 (-7675 675);
PAINT SKYBLUE (-7675 675);
FORCEPROP 2 LAST CDS_LIB pure_quanta
J 0
(-7725 875);
PAINT MONO (-7725 875);
DISPLAY INVISIBLE (-7725 875);
FORCEPROP 1 LAST PATH I26
J 0
(-7675 1025);
DISPLAY 0.978723 (-7675 1025);
PAINT WHITE (-7675 1025);
DISPLAY INVISIBLE (-7675 1025);
FORCEADD Q_CAP..1
(-7275 875);
FORCEPROP 1 LAST LOCATION C3929
J 0
(-7225 975);
DISPLAY 0.489362 (-7225 975);
PAINT SKYBLUE (-7225 975);
FORCEPROP 2 LAST $SEC 1
J 0
(-7225 1075);
DISPLAY 0.680851 (-7225 1075);
PAINT MONO (-7225 1075);
DISPLAY INVISIBLE (-7225 1075);
FORCEPROP 2 LAST CDS_SEC 1
J 0
(-7225 1075);
DISPLAY 1.021277 (-7225 1075);
DISPLAY INVISIBLE (-7225 1075);
FORCEPROP 1 LASTPIN (-7275 975) $PN 1
J 0
(-7265 955);
DISPLAY 0.489362 (-7265 955);
FORCEPROP 1 LASTPIN (-7275 775) $PN 2
J 0
(-7265 755);
DISPLAY 0.489362 (-7265 755);
FORCEPROP 1 LAST MATERIAL X6S
J 0
(-7225 775);
DISPLAY 0.489362 (-7225 775);
PAINT SKYBLUE (-7225 775);
FORCEPROP 1 LAST TOLERANCE 20%
J 0
(-7225 825);
DISPLAY 0.489362 (-7225 825);
PAINT SKYBLUE (-7225 825);
FORCEPROP 1 LAST VALUE 22UF
J 0
(-7225 925);
DISPLAY 0.489362 (-7225 925);
PAINT SKYBLUE (-7225 925);
FORCEPROP 1 LAST PART_NUMBER CH622KMEB02
J 0
(-7225 725);
DISPLAY 0.489362 (-7225 725);
PAINT SKYBLUE (-7225 725);
FORCEPROP 1 LAST VOLTAGE 4V
J 0
(-7225 875);
DISPLAY 0.489362 (-7225 875);
PAINT SKYBLUE (-7225 875);
FORCEPROP 1 LAST PACK_TYPE C0402
J 0
(-7225 675);
DISPLAY 0.489362 (-7225 675);
PAINT SKYBLUE (-7225 675);
FORCEPROP 2 LAST CDS_LIB pure_quanta
J 0
(-7275 875);
PAINT MONO (-7275 875);
DISPLAY INVISIBLE (-7275 875);
FORCEPROP 1 LAST PATH I27
J 0
(-7225 1025);
DISPLAY 0.978723 (-7225 1025);
PAINT WHITE (-7225 1025);
DISPLAY INVISIBLE (-7225 1025);
FORCEADD Q_CAP..1
(-8175 1575);
FORCEPROP 1 LAST LOCATION C2547
J 0
(-8125 1675);
DISPLAY 0.489362 (-8125 1675);
PAINT SKYBLUE (-8125 1675);
FORCEPROP 2 LAST $SEC 1
J 0
(-8125 1775);
DISPLAY 0.680851 (-8125 1775);
PAINT MONO (-8125 1775);
DISPLAY INVISIBLE (-8125 1775);
FORCEPROP 2 LAST CDS_SEC 1
J 0
(-8125 1775);
DISPLAY 1.021277 (-8125 1775);
DISPLAY INVISIBLE (-8125 1775);
FORCEPROP 1 LASTPIN (-8175 1675) $PN 1
J 0
(-8165 1655);
DISPLAY 0.489362 (-8165 1655);
FORCEPROP 1 LASTPIN (-8175 1475) $PN 2
J 0
(-8165 1455);
DISPLAY 0.489362 (-8165 1455);
FORCEPROP 1 LAST MATERIAL X6S
J 0
(-8125 1475);
DISPLAY 0.489362 (-8125 1475);
PAINT SKYBLUE (-8125 1475);
FORCEPROP 1 LAST TOLERANCE 20%
J 0
(-8125 1525);
DISPLAY 0.489362 (-8125 1525);
PAINT SKYBLUE (-8125 1525);
FORCEPROP 1 LAST VALUE 22UF
J 0
(-8125 1625);
DISPLAY 0.489362 (-8125 1625);
PAINT SKYBLUE (-8125 1625);
FORCEPROP 1 LAST PART_NUMBER CH622KMEB02
J 0
(-8125 1425);
DISPLAY 0.489362 (-8125 1425);
PAINT SKYBLUE (-8125 1425);
FORCEPROP 1 LAST VOLTAGE 4V
J 0
(-8125 1575);
DISPLAY 0.489362 (-8125 1575);
PAINT SKYBLUE (-8125 1575);
FORCEPROP 1 LAST PACK_TYPE C0402
J 0
(-8125 1375);
DISPLAY 0.489362 (-8125 1375);
PAINT SKYBLUE (-8125 1375);
FORCEPROP 2 LAST CDS_LIB pure_quanta
J 0
(-8175 1575);
PAINT MONO (-8175 1575);
DISPLAY INVISIBLE (-8175 1575);
FORCEPROP 1 LAST PATH I28
J 0
(-8125 1725);
DISPLAY 0.978723 (-8125 1725);
PAINT WHITE (-8125 1725);
DISPLAY INVISIBLE (-8125 1725);
FORCEADD Q_CAP..1
(-7725 1575);
FORCEPROP 1 LAST LOCATION C2554
J 0
(-7675 1675);
DISPLAY 0.489362 (-7675 1675);
PAINT SKYBLUE (-7675 1675);
FORCEPROP 2 LAST $SEC 1
J 0
(-7675 1775);
DISPLAY 0.680851 (-7675 1775);
PAINT MONO (-7675 1775);
DISPLAY INVISIBLE (-7675 1775);
FORCEPROP 2 LAST CDS_SEC 1
J 0
(-7675 1775);
DISPLAY 1.021277 (-7675 1775);
DISPLAY INVISIBLE (-7675 1775);
FORCEPROP 1 LASTPIN (-7725 1675) $PN 1
J 0
(-7715 1655);
DISPLAY 0.489362 (-7715 1655);
FORCEPROP 1 LASTPIN (-7725 1475) $PN 2
J 0
(-7715 1455);
DISPLAY 0.489362 (-7715 1455);
FORCEPROP 1 LAST MATERIAL X6S
J 0
(-7675 1475);
DISPLAY 0.489362 (-7675 1475);
PAINT SKYBLUE (-7675 1475);
FORCEPROP 1 LAST TOLERANCE 20%
J 0
(-7675 1525);
DISPLAY 0.489362 (-7675 1525);
PAINT SKYBLUE (-7675 1525);
FORCEPROP 1 LAST VALUE 22UF
J 0
(-7675 1625);
DISPLAY 0.489362 (-7675 1625);
PAINT SKYBLUE (-7675 1625);
FORCEPROP 1 LAST PART_NUMBER CH622KMEB02
J 0
(-7675 1425);
DISPLAY 0.489362 (-7675 1425);
PAINT SKYBLUE (-7675 1425);
FORCEPROP 1 LAST VOLTAGE 4V
J 0
(-7675 1575);
DISPLAY 0.489362 (-7675 1575);
PAINT SKYBLUE (-7675 1575);
FORCEPROP 1 LAST PACK_TYPE C0402
J 0
(-7675 1375);
DISPLAY 0.489362 (-7675 1375);
PAINT SKYBLUE (-7675 1375);
FORCEPROP 2 LAST CDS_LIB pure_quanta
J 0
(-7725 1575);
PAINT MONO (-7725 1575);
DISPLAY INVISIBLE (-7725 1575);
FORCEPROP 1 LAST PATH I29
J 0
(-7675 1725);
DISPLAY 0.978723 (-7675 1725);
PAINT WHITE (-7675 1725);
DISPLAY INVISIBLE (-7675 1725);
FORCEADD Q_CAP..1
(-8625 875);
FORCEPROP 1 LAST LOCATION C3926
J 0
(-8575 975);
DISPLAY 0.489362 (-8575 975);
PAINT SKYBLUE (-8575 975);
FORCEPROP 2 LAST $SEC 1
J 0
(-8575 1075);
DISPLAY 0.680851 (-8575 1075);
PAINT MONO (-8575 1075);
DISPLAY INVISIBLE (-8575 1075);
FORCEPROP 2 LAST CDS_SEC 1
J 0
(-8575 1075);
DISPLAY 1.021277 (-8575 1075);
DISPLAY INVISIBLE (-8575 1075);
FORCEPROP 1 LASTPIN (-8625 975) $PN 1
J 0
(-8615 955);
DISPLAY 0.489362 (-8615 955);
FORCEPROP 1 LASTPIN (-8625 775) $PN 2
J 0
(-8615 755);
DISPLAY 0.489362 (-8615 755);
FORCEPROP 1 LAST MATERIAL X6S
J 0
(-8575 775);
DISPLAY 0.489362 (-8575 775);
PAINT SKYBLUE (-8575 775);
FORCEPROP 1 LAST TOLERANCE 20%
J 0
(-8575 825);
DISPLAY 0.489362 (-8575 825);
PAINT SKYBLUE (-8575 825);
FORCEPROP 1 LAST VALUE 22UF
J 0
(-8575 925);
DISPLAY 0.489362 (-8575 925);
PAINT SKYBLUE (-8575 925);
FORCEPROP 1 LAST PART_NUMBER CH622KMEB02
J 0
(-8575 725);
DISPLAY 0.489362 (-8575 725);
PAINT SKYBLUE (-8575 725);
FORCEPROP 1 LAST VOLTAGE 4V
J 0
(-8575 875);
DISPLAY 0.489362 (-8575 875);
PAINT SKYBLUE (-8575 875);
FORCEPROP 1 LAST PACK_TYPE C0402
J 0
(-8575 675);
DISPLAY 0.489362 (-8575 675);
PAINT SKYBLUE (-8575 675);
FORCEPROP 2 LAST CDS_LIB pure_quanta
J 0
(-8625 875);
PAINT MONO (-8625 875);
DISPLAY INVISIBLE (-8625 875);
FORCEPROP 1 LAST PATH I3
J 0
(-8575 1025);
DISPLAY 0.978723 (-8575 1025);
PAINT WHITE (-8575 1025);
DISPLAY INVISIBLE (-8575 1025);
FORCEADD Q_CAP..1
(-7275 1575);
FORCEPROP 1 LAST LOCATION C2561
J 0
(-7225 1675);
DISPLAY 0.489362 (-7225 1675);
PAINT SKYBLUE (-7225 1675);
FORCEPROP 2 LAST $SEC 1
J 0
(-7225 1775);
DISPLAY 0.680851 (-7225 1775);
PAINT MONO (-7225 1775);
DISPLAY INVISIBLE (-7225 1775);
FORCEPROP 2 LAST CDS_SEC 1
J 0
(-7225 1775);
DISPLAY 1.021277 (-7225 1775);
DISPLAY INVISIBLE (-7225 1775);
FORCEPROP 1 LASTPIN (-7275 1675) $PN 1
J 0
(-7265 1655);
DISPLAY 0.489362 (-7265 1655);
FORCEPROP 1 LASTPIN (-7275 1475) $PN 2
J 0
(-7265 1455);
DISPLAY 0.489362 (-7265 1455);
FORCEPROP 1 LAST MATERIAL X6S
J 0
(-7225 1475);
DISPLAY 0.489362 (-7225 1475);
PAINT SKYBLUE (-7225 1475);
FORCEPROP 1 LAST TOLERANCE 20%
J 0
(-7225 1525);
DISPLAY 0.489362 (-7225 1525);
PAINT SKYBLUE (-7225 1525);
FORCEPROP 1 LAST VALUE 22UF
J 0
(-7225 1625);
DISPLAY 0.489362 (-7225 1625);
PAINT SKYBLUE (-7225 1625);
FORCEPROP 1 LAST PART_NUMBER CH622KMEB02
J 0
(-7225 1425);
DISPLAY 0.489362 (-7225 1425);
PAINT SKYBLUE (-7225 1425);
FORCEPROP 1 LAST VOLTAGE 4V
J 0
(-7225 1575);
DISPLAY 0.489362 (-7225 1575);
PAINT SKYBLUE (-7225 1575);
FORCEPROP 1 LAST PACK_TYPE C0402
J 0
(-7225 1375);
DISPLAY 0.489362 (-7225 1375);
PAINT SKYBLUE (-7225 1375);
FORCEPROP 2 LAST CDS_LIB pure_quanta
J 0
(-7275 1575);
PAINT MONO (-7275 1575);
DISPLAY INVISIBLE (-7275 1575);
FORCEPROP 1 LAST PATH I30
J 0
(-7225 1725);
DISPLAY 0.978723 (-7225 1725);
PAINT WHITE (-7225 1725);
DISPLAY INVISIBLE (-7225 1725);
FORCEADD Q_CAP..1
(-6825 875);
FORCEPROP 1 LAST LOCATION C3930
J 0
(-6775 975);
DISPLAY 0.489362 (-6775 975);
PAINT SKYBLUE (-6775 975);
FORCEPROP 2 LAST $SEC 1
J 0
(-6775 1075);
DISPLAY 0.680851 (-6775 1075);
PAINT MONO (-6775 1075);
DISPLAY INVISIBLE (-6775 1075);
FORCEPROP 2 LAST CDS_SEC 1
J 0
(-6775 1075);
DISPLAY 1.021277 (-6775 1075);
DISPLAY INVISIBLE (-6775 1075);
FORCEPROP 1 LASTPIN (-6825 975) $PN 1
J 0
(-6815 955);
DISPLAY 0.489362 (-6815 955);
FORCEPROP 1 LASTPIN (-6825 775) $PN 2
J 0
(-6815 755);
DISPLAY 0.489362 (-6815 755);
FORCEPROP 1 LAST MATERIAL X6S
J 0
(-6775 775);
DISPLAY 0.489362 (-6775 775);
PAINT SKYBLUE (-6775 775);
FORCEPROP 1 LAST TOLERANCE 20%
J 0
(-6775 825);
DISPLAY 0.489362 (-6775 825);
PAINT SKYBLUE (-6775 825);
FORCEPROP 1 LAST VALUE 22UF
J 0
(-6775 925);
DISPLAY 0.489362 (-6775 925);
PAINT SKYBLUE (-6775 925);
FORCEPROP 1 LAST PART_NUMBER CH622KMEB02
J 0
(-6775 725);
DISPLAY 0.489362 (-6775 725);
PAINT SKYBLUE (-6775 725);
FORCEPROP 1 LAST VOLTAGE 4V
J 0
(-6775 875);
DISPLAY 0.489362 (-6775 875);
PAINT SKYBLUE (-6775 875);
FORCEPROP 1 LAST PACK_TYPE C0402
J 0
(-6775 675);
DISPLAY 0.489362 (-6775 675);
PAINT SKYBLUE (-6775 675);
FORCEPROP 2 LAST CDS_LIB pure_quanta
J 0
(-6825 875);
PAINT MONO (-6825 875);
DISPLAY INVISIBLE (-6825 875);
FORCEPROP 1 LAST PATH I31
J 0
(-6775 1025);
DISPLAY 0.978723 (-6775 1025);
PAINT WHITE (-6775 1025);
DISPLAY INVISIBLE (-6775 1025);
FORCEADD UNIVERSAL_GND..1
(-6375 500);
FORCEPROP 3 LASTPIN (-6375 550) SIG_NAME GND\g
J 0
(-6365 560);
DISPLAY 0.659574 (-6365 560);
PAINT MONO (-6365 560);
DISPLAY INVISIBLE (-6365 560);
FORCEPROP 2 LAST CDS_LIB pure_quanta_power
J 0
(-6375 500);
PAINT MONO (-6375 500);
DISPLAY INVISIBLE (-6375 500);
FORCEPROP 1 LAST PATH I32
J 0
(-6300 500);
DISPLAY 0.872340 (-6300 500);
PAINT AQUA (-6300 500);
DISPLAY INVISIBLE (-6300 500);
FORCEPROP 1 LAST HDL_POWER GND
J 1
(-6350 425);
DISPLAY 0.872340 (-6350 425);
PAINT GREEN (-6350 425);
DISPLAY INVISIBLE (-6350 425);
FORCEADD Q_CAP..1
(-6375 875);
FORCEPROP 1 LAST LOCATION C3931
J 0
(-6325 975);
DISPLAY 0.489362 (-6325 975);
PAINT SKYBLUE (-6325 975);
FORCEPROP 2 LAST $SEC 1
J 0
(-6325 1075);
DISPLAY 0.680851 (-6325 1075);
PAINT MONO (-6325 1075);
DISPLAY INVISIBLE (-6325 1075);
FORCEPROP 2 LAST CDS_SEC 1
J 0
(-6325 1075);
DISPLAY 1.021277 (-6325 1075);
DISPLAY INVISIBLE (-6325 1075);
FORCEPROP 1 LASTPIN (-6375 975) $PN 1
J 0
(-6365 955);
DISPLAY 0.489362 (-6365 955);
FORCEPROP 1 LASTPIN (-6375 775) $PN 2
J 0
(-6365 755);
DISPLAY 0.489362 (-6365 755);
FORCEPROP 1 LAST MATERIAL X6S
J 0
(-6325 775);
DISPLAY 0.489362 (-6325 775);
PAINT SKYBLUE (-6325 775);
FORCEPROP 1 LAST TOLERANCE 20%
J 0
(-6325 825);
DISPLAY 0.489362 (-6325 825);
PAINT SKYBLUE (-6325 825);
FORCEPROP 1 LAST VALUE 22UF
J 0
(-6325 925);
DISPLAY 0.489362 (-6325 925);
PAINT SKYBLUE (-6325 925);
FORCEPROP 1 LAST PART_NUMBER CH622KMEB02
J 0
(-6325 725);
DISPLAY 0.489362 (-6325 725);
PAINT SKYBLUE (-6325 725);
FORCEPROP 1 LAST VOLTAGE 4V
J 0
(-6325 875);
DISPLAY 0.489362 (-6325 875);
PAINT SKYBLUE (-6325 875);
FORCEPROP 1 LAST PACK_TYPE C0402
J 0
(-6325 675);
DISPLAY 0.489362 (-6325 675);
PAINT SKYBLUE (-6325 675);
FORCEPROP 2 LAST CDS_LIB pure_quanta
J 0
(-6375 875);
PAINT MONO (-6375 875);
DISPLAY INVISIBLE (-6375 875);
FORCEPROP 1 LAST PATH I33
J 0
(-6325 1025);
DISPLAY 0.978723 (-6325 1025);
PAINT WHITE (-6325 1025);
DISPLAY INVISIBLE (-6325 1025);
FORCEADD Q_CAP..1
(-6825 1575);
FORCEPROP 1 LAST LOCATION C2568
J 0
(-6775 1675);
DISPLAY 0.489362 (-6775 1675);
PAINT SKYBLUE (-6775 1675);
FORCEPROP 2 LAST $SEC 1
J 0
(-6775 1775);
DISPLAY 0.680851 (-6775 1775);
PAINT MONO (-6775 1775);
DISPLAY INVISIBLE (-6775 1775);
FORCEPROP 2 LAST CDS_SEC 1
J 0
(-6775 1775);
DISPLAY 1.021277 (-6775 1775);
DISPLAY INVISIBLE (-6775 1775);
FORCEPROP 1 LASTPIN (-6825 1675) $PN 1
J 0
(-6815 1655);
DISPLAY 0.489362 (-6815 1655);
FORCEPROP 1 LASTPIN (-6825 1475) $PN 2
J 0
(-6815 1455);
DISPLAY 0.489362 (-6815 1455);
FORCEPROP 1 LAST MATERIAL X6S
J 0
(-6775 1475);
DISPLAY 0.489362 (-6775 1475);
PAINT SKYBLUE (-6775 1475);
FORCEPROP 1 LAST TOLERANCE 20%
J 0
(-6775 1525);
DISPLAY 0.489362 (-6775 1525);
PAINT SKYBLUE (-6775 1525);
FORCEPROP 1 LAST VALUE 22UF
J 0
(-6775 1625);
DISPLAY 0.489362 (-6775 1625);
PAINT SKYBLUE (-6775 1625);
FORCEPROP 1 LAST PART_NUMBER CH622KMEB02
J 0
(-6775 1425);
DISPLAY 0.489362 (-6775 1425);
PAINT SKYBLUE (-6775 1425);
FORCEPROP 1 LAST VOLTAGE 4V
J 0
(-6775 1575);
DISPLAY 0.489362 (-6775 1575);
PAINT SKYBLUE (-6775 1575);
FORCEPROP 1 LAST PACK_TYPE C0402
J 0
(-6775 1375);
DISPLAY 0.489362 (-6775 1375);
PAINT SKYBLUE (-6775 1375);
FORCEPROP 2 LAST CDS_LIB pure_quanta
J 0
(-6825 1575);
PAINT MONO (-6825 1575);
DISPLAY INVISIBLE (-6825 1575);
FORCEPROP 1 LAST PATH I34
J 0
(-6775 1725);
DISPLAY 0.978723 (-6775 1725);
PAINT WHITE (-6775 1725);
DISPLAY INVISIBLE (-6775 1725);
FORCEADD Q_CAP..1
(-6375 1575);
FORCEPROP 1 LAST LOCATION C2575
J 0
(-6325 1675);
DISPLAY 0.489362 (-6325 1675);
PAINT SKYBLUE (-6325 1675);
FORCEPROP 2 LAST $SEC 1
J 0
(-6325 1775);
DISPLAY 0.680851 (-6325 1775);
PAINT MONO (-6325 1775);
DISPLAY INVISIBLE (-6325 1775);
FORCEPROP 2 LAST CDS_SEC 1
J 0
(-6325 1775);
DISPLAY 1.021277 (-6325 1775);
DISPLAY INVISIBLE (-6325 1775);
FORCEPROP 1 LASTPIN (-6375 1675) $PN 1
J 0
(-6365 1655);
DISPLAY 0.489362 (-6365 1655);
FORCEPROP 1 LASTPIN (-6375 1475) $PN 2
J 0
(-6365 1455);
DISPLAY 0.489362 (-6365 1455);
FORCEPROP 1 LAST MATERIAL X6S
J 0
(-6325 1475);
DISPLAY 0.489362 (-6325 1475);
PAINT SKYBLUE (-6325 1475);
FORCEPROP 1 LAST TOLERANCE 20%
J 0
(-6325 1525);
DISPLAY 0.489362 (-6325 1525);
PAINT SKYBLUE (-6325 1525);
FORCEPROP 1 LAST VALUE 22UF
J 0
(-6325 1625);
DISPLAY 0.489362 (-6325 1625);
PAINT SKYBLUE (-6325 1625);
FORCEPROP 1 LAST PART_NUMBER CH622KMEB02
J 0
(-6325 1425);
DISPLAY 0.489362 (-6325 1425);
PAINT SKYBLUE (-6325 1425);
FORCEPROP 1 LAST VOLTAGE 4V
J 0
(-6325 1575);
DISPLAY 0.489362 (-6325 1575);
PAINT SKYBLUE (-6325 1575);
FORCEPROP 1 LAST PACK_TYPE C0402
J 0
(-6325 1375);
DISPLAY 0.489362 (-6325 1375);
PAINT SKYBLUE (-6325 1375);
FORCEPROP 2 LAST CDS_LIB pure_quanta
J 0
(-6375 1575);
PAINT MONO (-6375 1575);
DISPLAY INVISIBLE (-6375 1575);
FORCEPROP 1 LAST PATH I35
J 0
(-6325 1725);
DISPLAY 0.978723 (-6325 1725);
PAINT WHITE (-6325 1725);
DISPLAY INVISIBLE (-6325 1725);
FORCEADD Q_CAP..1
(-8175 2300);
FORCEPROP 1 LAST LOCATION C2546
J 0
(-8125 2400);
DISPLAY 0.489362 (-8125 2400);
PAINT SKYBLUE (-8125 2400);
FORCEPROP 2 LAST $SEC 1
J 0
(-8125 2500);
DISPLAY 0.680851 (-8125 2500);
PAINT MONO (-8125 2500);
DISPLAY INVISIBLE (-8125 2500);
FORCEPROP 2 LAST CDS_SEC 1
J 0
(-8125 2500);
DISPLAY 1.021277 (-8125 2500);
DISPLAY INVISIBLE (-8125 2500);
FORCEPROP 1 LASTPIN (-8175 2400) $PN 1
J 0
(-8165 2380);
DISPLAY 0.489362 (-8165 2380);
FORCEPROP 1 LASTPIN (-8175 2200) $PN 2
J 0
(-8165 2180);
DISPLAY 0.489362 (-8165 2180);
FORCEPROP 1 LAST MATERIAL X6S
J 0
(-8125 2200);
DISPLAY 0.489362 (-8125 2200);
PAINT SKYBLUE (-8125 2200);
FORCEPROP 1 LAST TOLERANCE 20%
J 0
(-8125 2250);
DISPLAY 0.489362 (-8125 2250);
PAINT SKYBLUE (-8125 2250);
FORCEPROP 1 LAST VALUE 22UF
J 0
(-8125 2350);
DISPLAY 0.489362 (-8125 2350);
PAINT SKYBLUE (-8125 2350);
FORCEPROP 1 LAST PART_NUMBER CH622KMEB02
J 0
(-8125 2150);
DISPLAY 0.489362 (-8125 2150);
PAINT SKYBLUE (-8125 2150);
FORCEPROP 1 LAST VOLTAGE 4V
J 0
(-8125 2300);
DISPLAY 0.489362 (-8125 2300);
PAINT SKYBLUE (-8125 2300);
FORCEPROP 1 LAST PACK_TYPE C0402
J 0
(-8125 2100);
DISPLAY 0.489362 (-8125 2100);
PAINT SKYBLUE (-8125 2100);
FORCEPROP 2 LAST CDS_LIB pure_quanta
J 0
(-8175 2300);
PAINT MONO (-8175 2300);
DISPLAY INVISIBLE (-8175 2300);
FORCEPROP 1 LAST PATH I36
J 0
(-8125 2450);
DISPLAY 0.978723 (-8125 2450);
PAINT WHITE (-8125 2450);
DISPLAY INVISIBLE (-8125 2450);
FORCEADD Q_CAP..1
(-8175 3000);
FORCEPROP 1 LAST LOCATION C2545
J 0
(-8125 3100);
DISPLAY 0.489362 (-8125 3100);
PAINT SKYBLUE (-8125 3100);
FORCEPROP 2 LAST $SEC 1
J 0
(-8125 3200);
DISPLAY 0.680851 (-8125 3200);
PAINT MONO (-8125 3200);
DISPLAY INVISIBLE (-8125 3200);
FORCEPROP 2 LAST CDS_SEC 1
J 0
(-8125 3200);
DISPLAY 1.021277 (-8125 3200);
DISPLAY INVISIBLE (-8125 3200);
FORCEPROP 1 LASTPIN (-8175 3100) $PN 1
J 0
(-8165 3080);
DISPLAY 0.489362 (-8165 3080);
FORCEPROP 1 LASTPIN (-8175 2900) $PN 2
J 0
(-8165 2880);
DISPLAY 0.489362 (-8165 2880);
FORCEPROP 1 LAST MATERIAL X6S
J 0
(-8125 2900);
DISPLAY 0.489362 (-8125 2900);
PAINT SKYBLUE (-8125 2900);
FORCEPROP 1 LAST TOLERANCE 20%
J 0
(-8125 2950);
DISPLAY 0.489362 (-8125 2950);
PAINT SKYBLUE (-8125 2950);
FORCEPROP 1 LAST VALUE 22UF
J 0
(-8125 3050);
DISPLAY 0.489362 (-8125 3050);
PAINT SKYBLUE (-8125 3050);
FORCEPROP 1 LAST PART_NUMBER CH622KMEB02
J 0
(-8125 2850);
DISPLAY 0.489362 (-8125 2850);
PAINT SKYBLUE (-8125 2850);
FORCEPROP 1 LAST VOLTAGE 4V
J 0
(-8125 3000);
DISPLAY 0.489362 (-8125 3000);
PAINT SKYBLUE (-8125 3000);
FORCEPROP 1 LAST PACK_TYPE C0402
J 0
(-8125 2800);
DISPLAY 0.489362 (-8125 2800);
PAINT SKYBLUE (-8125 2800);
FORCEPROP 2 LAST CDS_LIB pure_quanta
J 0
(-8175 3000);
PAINT MONO (-8175 3000);
DISPLAY INVISIBLE (-8175 3000);
FORCEPROP 1 LAST PATH I37
J 0
(-8125 3150);
DISPLAY 0.978723 (-8125 3150);
PAINT WHITE (-8125 3150);
DISPLAY INVISIBLE (-8125 3150);
FORCEADD Q_CAP..1
(-7725 2300);
FORCEPROP 1 LAST LOCATION C2553
J 0
(-7675 2400);
DISPLAY 0.489362 (-7675 2400);
PAINT SKYBLUE (-7675 2400);
FORCEPROP 2 LAST $SEC 1
J 0
(-7675 2500);
DISPLAY 0.680851 (-7675 2500);
PAINT MONO (-7675 2500);
DISPLAY INVISIBLE (-7675 2500);
FORCEPROP 2 LAST CDS_SEC 1
J 0
(-7675 2500);
DISPLAY 1.021277 (-7675 2500);
DISPLAY INVISIBLE (-7675 2500);
FORCEPROP 1 LASTPIN (-7725 2400) $PN 1
J 0
(-7715 2380);
DISPLAY 0.489362 (-7715 2380);
FORCEPROP 1 LASTPIN (-7725 2200) $PN 2
J 0
(-7715 2180);
DISPLAY 0.489362 (-7715 2180);
FORCEPROP 1 LAST MATERIAL X6S
J 0
(-7675 2200);
DISPLAY 0.489362 (-7675 2200);
PAINT SKYBLUE (-7675 2200);
FORCEPROP 1 LAST TOLERANCE 20%
J 0
(-7675 2250);
DISPLAY 0.489362 (-7675 2250);
PAINT SKYBLUE (-7675 2250);
FORCEPROP 1 LAST VALUE 22UF
J 0
(-7675 2350);
DISPLAY 0.489362 (-7675 2350);
PAINT SKYBLUE (-7675 2350);
FORCEPROP 1 LAST PART_NUMBER CH622KMEB02
J 0
(-7675 2150);
DISPLAY 0.489362 (-7675 2150);
PAINT SKYBLUE (-7675 2150);
FORCEPROP 1 LAST VOLTAGE 4V
J 0
(-7675 2300);
DISPLAY 0.489362 (-7675 2300);
PAINT SKYBLUE (-7675 2300);
FORCEPROP 1 LAST PACK_TYPE C0402
J 0
(-7675 2100);
DISPLAY 0.489362 (-7675 2100);
PAINT SKYBLUE (-7675 2100);
FORCEPROP 2 LAST CDS_LIB pure_quanta
J 0
(-7725 2300);
PAINT MONO (-7725 2300);
DISPLAY INVISIBLE (-7725 2300);
FORCEPROP 1 LAST PATH I38
J 0
(-7675 2450);
DISPLAY 0.978723 (-7675 2450);
PAINT WHITE (-7675 2450);
DISPLAY INVISIBLE (-7675 2450);
FORCEADD Q_CAP..1
(-7275 2300);
FORCEPROP 1 LAST LOCATION C2560
J 0
(-7225 2400);
DISPLAY 0.489362 (-7225 2400);
PAINT SKYBLUE (-7225 2400);
FORCEPROP 2 LAST $SEC 1
J 0
(-7225 2500);
DISPLAY 0.680851 (-7225 2500);
PAINT MONO (-7225 2500);
DISPLAY INVISIBLE (-7225 2500);
FORCEPROP 2 LAST CDS_SEC 1
J 0
(-7225 2500);
DISPLAY 1.021277 (-7225 2500);
DISPLAY INVISIBLE (-7225 2500);
FORCEPROP 1 LASTPIN (-7275 2400) $PN 1
J 0
(-7265 2380);
DISPLAY 0.489362 (-7265 2380);
FORCEPROP 1 LASTPIN (-7275 2200) $PN 2
J 0
(-7265 2180);
DISPLAY 0.489362 (-7265 2180);
FORCEPROP 1 LAST MATERIAL X6S
J 0
(-7225 2200);
DISPLAY 0.489362 (-7225 2200);
PAINT SKYBLUE (-7225 2200);
FORCEPROP 1 LAST TOLERANCE 20%
J 0
(-7225 2250);
DISPLAY 0.489362 (-7225 2250);
PAINT SKYBLUE (-7225 2250);
FORCEPROP 1 LAST VALUE 22UF
J 0
(-7225 2350);
DISPLAY 0.489362 (-7225 2350);
PAINT SKYBLUE (-7225 2350);
FORCEPROP 1 LAST PART_NUMBER CH622KMEB02
J 0
(-7225 2150);
DISPLAY 0.489362 (-7225 2150);
PAINT SKYBLUE (-7225 2150);
FORCEPROP 1 LAST VOLTAGE 4V
J 0
(-7225 2300);
DISPLAY 0.489362 (-7225 2300);
PAINT SKYBLUE (-7225 2300);
FORCEPROP 1 LAST PACK_TYPE C0402
J 0
(-7225 2100);
DISPLAY 0.489362 (-7225 2100);
PAINT SKYBLUE (-7225 2100);
FORCEPROP 2 LAST CDS_LIB pure_quanta
J 0
(-7275 2300);
PAINT MONO (-7275 2300);
DISPLAY INVISIBLE (-7275 2300);
FORCEPROP 1 LAST PATH I39
J 0
(-7225 2450);
DISPLAY 0.978723 (-7225 2450);
PAINT WHITE (-7225 2450);
DISPLAY INVISIBLE (-7225 2450);
FORCEADD Q_CAP..1
(-9075 1575);
FORCEPROP 1 LAST LOCATION C2533
J 0
(-9025 1675);
DISPLAY 0.489362 (-9025 1675);
PAINT SKYBLUE (-9025 1675);
FORCEPROP 2 LAST $SEC 1
J 0
(-9025 1775);
DISPLAY 0.680851 (-9025 1775);
PAINT MONO (-9025 1775);
DISPLAY INVISIBLE (-9025 1775);
FORCEPROP 2 LAST CDS_SEC 1
J 0
(-9025 1775);
DISPLAY 1.021277 (-9025 1775);
DISPLAY INVISIBLE (-9025 1775);
FORCEPROP 1 LASTPIN (-9075 1675) $PN 1
J 0
(-9065 1655);
DISPLAY 0.489362 (-9065 1655);
FORCEPROP 1 LASTPIN (-9075 1475) $PN 2
J 0
(-9065 1455);
DISPLAY 0.489362 (-9065 1455);
FORCEPROP 1 LAST MATERIAL X6S
J 0
(-9025 1475);
DISPLAY 0.489362 (-9025 1475);
PAINT SKYBLUE (-9025 1475);
FORCEPROP 1 LAST TOLERANCE 20%
J 0
(-9025 1525);
DISPLAY 0.489362 (-9025 1525);
PAINT SKYBLUE (-9025 1525);
FORCEPROP 1 LAST VALUE 22UF
J 0
(-9025 1625);
DISPLAY 0.489362 (-9025 1625);
PAINT SKYBLUE (-9025 1625);
FORCEPROP 1 LAST PART_NUMBER CH622KMEB02
J 0
(-9025 1425);
DISPLAY 0.489362 (-9025 1425);
PAINT SKYBLUE (-9025 1425);
FORCEPROP 1 LAST VOLTAGE 4V
J 0
(-9025 1575);
DISPLAY 0.489362 (-9025 1575);
PAINT SKYBLUE (-9025 1575);
FORCEPROP 1 LAST PACK_TYPE C0402
J 0
(-9025 1375);
DISPLAY 0.489362 (-9025 1375);
PAINT SKYBLUE (-9025 1375);
FORCEPROP 2 LAST CDS_LIB pure_quanta
J 0
(-9075 1575);
PAINT MONO (-9075 1575);
DISPLAY INVISIBLE (-9075 1575);
FORCEPROP 1 LAST PATH I4
J 0
(-9025 1725);
DISPLAY 0.978723 (-9025 1725);
PAINT WHITE (-9025 1725);
DISPLAY INVISIBLE (-9025 1725);
FORCEADD Q_CAP..1
(-7725 3000);
FORCEPROP 1 LAST LOCATION C2552
J 0
(-7675 3100);
DISPLAY 0.489362 (-7675 3100);
PAINT SKYBLUE (-7675 3100);
FORCEPROP 2 LAST $SEC 1
J 0
(-7675 3200);
DISPLAY 0.680851 (-7675 3200);
PAINT MONO (-7675 3200);
DISPLAY INVISIBLE (-7675 3200);
FORCEPROP 2 LAST CDS_SEC 1
J 0
(-7675 3200);
DISPLAY 1.021277 (-7675 3200);
DISPLAY INVISIBLE (-7675 3200);
FORCEPROP 1 LASTPIN (-7725 3100) $PN 1
J 0
(-7715 3080);
DISPLAY 0.489362 (-7715 3080);
FORCEPROP 1 LASTPIN (-7725 2900) $PN 2
J 0
(-7715 2880);
DISPLAY 0.489362 (-7715 2880);
FORCEPROP 1 LAST MATERIAL X6S
J 0
(-7675 2900);
DISPLAY 0.489362 (-7675 2900);
PAINT SKYBLUE (-7675 2900);
FORCEPROP 1 LAST TOLERANCE 20%
J 0
(-7675 2950);
DISPLAY 0.489362 (-7675 2950);
PAINT SKYBLUE (-7675 2950);
FORCEPROP 1 LAST VALUE 22UF
J 0
(-7675 3050);
DISPLAY 0.489362 (-7675 3050);
PAINT SKYBLUE (-7675 3050);
FORCEPROP 1 LAST PART_NUMBER CH622KMEB02
J 0
(-7675 2850);
DISPLAY 0.489362 (-7675 2850);
PAINT SKYBLUE (-7675 2850);
FORCEPROP 1 LAST VOLTAGE 4V
J 0
(-7675 3000);
DISPLAY 0.489362 (-7675 3000);
PAINT SKYBLUE (-7675 3000);
FORCEPROP 1 LAST PACK_TYPE C0402
J 0
(-7675 2800);
DISPLAY 0.489362 (-7675 2800);
PAINT SKYBLUE (-7675 2800);
FORCEPROP 2 LAST CDS_LIB pure_quanta
J 0
(-7725 3000);
PAINT MONO (-7725 3000);
DISPLAY INVISIBLE (-7725 3000);
FORCEPROP 1 LAST PATH I40
J 0
(-7675 3150);
DISPLAY 0.978723 (-7675 3150);
PAINT WHITE (-7675 3150);
DISPLAY INVISIBLE (-7675 3150);
FORCEADD Q_CAP..1
(-7275 3000);
FORCEPROP 1 LAST LOCATION C2559
J 0
(-7225 3100);
DISPLAY 0.489362 (-7225 3100);
PAINT SKYBLUE (-7225 3100);
FORCEPROP 2 LAST $SEC 1
J 0
(-7225 3200);
DISPLAY 0.680851 (-7225 3200);
PAINT MONO (-7225 3200);
DISPLAY INVISIBLE (-7225 3200);
FORCEPROP 2 LAST CDS_SEC 1
J 0
(-7225 3200);
DISPLAY 1.021277 (-7225 3200);
DISPLAY INVISIBLE (-7225 3200);
FORCEPROP 1 LASTPIN (-7275 3100) $PN 1
J 0
(-7265 3080);
DISPLAY 0.489362 (-7265 3080);
FORCEPROP 1 LASTPIN (-7275 2900) $PN 2
J 0
(-7265 2880);
DISPLAY 0.489362 (-7265 2880);
FORCEPROP 1 LAST MATERIAL X6S
J 0
(-7225 2900);
DISPLAY 0.489362 (-7225 2900);
PAINT SKYBLUE (-7225 2900);
FORCEPROP 1 LAST TOLERANCE 20%
J 0
(-7225 2950);
DISPLAY 0.489362 (-7225 2950);
PAINT SKYBLUE (-7225 2950);
FORCEPROP 1 LAST VALUE 22UF
J 0
(-7225 3050);
DISPLAY 0.489362 (-7225 3050);
PAINT SKYBLUE (-7225 3050);
FORCEPROP 1 LAST PART_NUMBER CH622KMEB02
J 0
(-7225 2850);
DISPLAY 0.489362 (-7225 2850);
PAINT SKYBLUE (-7225 2850);
FORCEPROP 1 LAST VOLTAGE 4V
J 0
(-7225 3000);
DISPLAY 0.489362 (-7225 3000);
PAINT SKYBLUE (-7225 3000);
FORCEPROP 1 LAST PACK_TYPE C0402
J 0
(-7225 2800);
DISPLAY 0.489362 (-7225 2800);
PAINT SKYBLUE (-7225 2800);
FORCEPROP 2 LAST CDS_LIB pure_quanta
J 0
(-7275 3000);
PAINT MONO (-7275 3000);
DISPLAY INVISIBLE (-7275 3000);
FORCEPROP 1 LAST PATH I41
J 0
(-7225 3150);
DISPLAY 0.978723 (-7225 3150);
PAINT WHITE (-7225 3150);
DISPLAY INVISIBLE (-7225 3150);
FORCEADD Q_CAP..1
(-8175 3725);
FORCEPROP 1 LAST LOCATION C2544
J 0
(-8125 3825);
DISPLAY 0.489362 (-8125 3825);
PAINT SKYBLUE (-8125 3825);
FORCEPROP 2 LAST $SEC 1
J 0
(-8125 3925);
DISPLAY 0.680851 (-8125 3925);
PAINT MONO (-8125 3925);
DISPLAY INVISIBLE (-8125 3925);
FORCEPROP 2 LAST CDS_SEC 1
J 0
(-8125 3925);
DISPLAY 1.021277 (-8125 3925);
DISPLAY INVISIBLE (-8125 3925);
FORCEPROP 1 LASTPIN (-8175 3825) $PN 1
J 0
(-8165 3805);
DISPLAY 0.489362 (-8165 3805);
FORCEPROP 1 LASTPIN (-8175 3625) $PN 2
J 0
(-8165 3605);
DISPLAY 0.489362 (-8165 3605);
FORCEPROP 1 LAST MATERIAL X6S
J 0
(-8125 3625);
DISPLAY 0.489362 (-8125 3625);
PAINT SKYBLUE (-8125 3625);
FORCEPROP 1 LAST TOLERANCE 20%
J 0
(-8125 3675);
DISPLAY 0.489362 (-8125 3675);
PAINT SKYBLUE (-8125 3675);
FORCEPROP 1 LAST VALUE 22UF
J 0
(-8125 3775);
DISPLAY 0.489362 (-8125 3775);
PAINT SKYBLUE (-8125 3775);
FORCEPROP 1 LAST PART_NUMBER CH622KMEB02
J 0
(-8125 3575);
DISPLAY 0.489362 (-8125 3575);
PAINT SKYBLUE (-8125 3575);
FORCEPROP 1 LAST VOLTAGE 4V
J 0
(-8125 3725);
DISPLAY 0.489362 (-8125 3725);
PAINT SKYBLUE (-8125 3725);
FORCEPROP 1 LAST PACK_TYPE C0402
J 0
(-8125 3525);
DISPLAY 0.489362 (-8125 3525);
PAINT SKYBLUE (-8125 3525);
FORCEPROP 2 LAST CDS_LIB pure_quanta
J 0
(-8175 3725);
PAINT MONO (-8175 3725);
DISPLAY INVISIBLE (-8175 3725);
FORCEPROP 1 LAST PATH I42
J 0
(-8125 3875);
DISPLAY 0.978723 (-8125 3875);
PAINT WHITE (-8125 3875);
DISPLAY INVISIBLE (-8125 3875);
FORCEADD Q_CAP..1
(-7725 3725);
FORCEPROP 1 LAST LOCATION C2551
J 0
(-7675 3825);
DISPLAY 0.489362 (-7675 3825);
PAINT SKYBLUE (-7675 3825);
FORCEPROP 2 LAST $SEC 1
J 0
(-7675 3925);
DISPLAY 0.680851 (-7675 3925);
PAINT MONO (-7675 3925);
DISPLAY INVISIBLE (-7675 3925);
FORCEPROP 2 LAST CDS_SEC 1
J 0
(-7675 3925);
DISPLAY 1.021277 (-7675 3925);
DISPLAY INVISIBLE (-7675 3925);
FORCEPROP 1 LASTPIN (-7725 3825) $PN 1
J 0
(-7715 3805);
DISPLAY 0.489362 (-7715 3805);
FORCEPROP 1 LASTPIN (-7725 3625) $PN 2
J 0
(-7715 3605);
DISPLAY 0.489362 (-7715 3605);
FORCEPROP 1 LAST MATERIAL X6S
J 0
(-7675 3625);
DISPLAY 0.489362 (-7675 3625);
PAINT SKYBLUE (-7675 3625);
FORCEPROP 1 LAST TOLERANCE 20%
J 0
(-7675 3675);
DISPLAY 0.489362 (-7675 3675);
PAINT SKYBLUE (-7675 3675);
FORCEPROP 1 LAST VALUE 22UF
J 0
(-7675 3775);
DISPLAY 0.489362 (-7675 3775);
PAINT SKYBLUE (-7675 3775);
FORCEPROP 1 LAST PART_NUMBER CH622KMEB02
J 0
(-7675 3575);
DISPLAY 0.489362 (-7675 3575);
PAINT SKYBLUE (-7675 3575);
FORCEPROP 1 LAST VOLTAGE 4V
J 0
(-7675 3725);
DISPLAY 0.489362 (-7675 3725);
PAINT SKYBLUE (-7675 3725);
FORCEPROP 1 LAST PACK_TYPE C0402
J 0
(-7675 3525);
DISPLAY 0.489362 (-7675 3525);
PAINT SKYBLUE (-7675 3525);
FORCEPROP 2 LAST CDS_LIB pure_quanta
J 0
(-7725 3725);
PAINT MONO (-7725 3725);
DISPLAY INVISIBLE (-7725 3725);
FORCEPROP 1 LAST PATH I43
J 0
(-7675 3875);
DISPLAY 0.978723 (-7675 3875);
PAINT WHITE (-7675 3875);
DISPLAY INVISIBLE (-7675 3875);
FORCEADD Q_CAP..1
(-7275 3725);
FORCEPROP 1 LAST LOCATION C2558
J 0
(-7225 3825);
DISPLAY 0.489362 (-7225 3825);
PAINT SKYBLUE (-7225 3825);
FORCEPROP 2 LAST $SEC 1
J 0
(-7225 3925);
DISPLAY 0.680851 (-7225 3925);
PAINT MONO (-7225 3925);
DISPLAY INVISIBLE (-7225 3925);
FORCEPROP 2 LAST CDS_SEC 1
J 0
(-7225 3925);
DISPLAY 1.021277 (-7225 3925);
DISPLAY INVISIBLE (-7225 3925);
FORCEPROP 1 LASTPIN (-7275 3825) $PN 1
J 0
(-7265 3805);
DISPLAY 0.489362 (-7265 3805);
FORCEPROP 1 LASTPIN (-7275 3625) $PN 2
J 0
(-7265 3605);
DISPLAY 0.489362 (-7265 3605);
FORCEPROP 1 LAST MATERIAL X6S
J 0
(-7225 3625);
DISPLAY 0.489362 (-7225 3625);
PAINT SKYBLUE (-7225 3625);
FORCEPROP 1 LAST TOLERANCE 20%
J 0
(-7225 3675);
DISPLAY 0.489362 (-7225 3675);
PAINT SKYBLUE (-7225 3675);
FORCEPROP 1 LAST VALUE 22UF
J 0
(-7225 3775);
DISPLAY 0.489362 (-7225 3775);
PAINT SKYBLUE (-7225 3775);
FORCEPROP 1 LAST PART_NUMBER CH622KMEB02
J 0
(-7225 3575);
DISPLAY 0.489362 (-7225 3575);
PAINT SKYBLUE (-7225 3575);
FORCEPROP 1 LAST VOLTAGE 4V
J 0
(-7225 3725);
DISPLAY 0.489362 (-7225 3725);
PAINT SKYBLUE (-7225 3725);
FORCEPROP 1 LAST PACK_TYPE C0402
J 0
(-7225 3525);
DISPLAY 0.489362 (-7225 3525);
PAINT SKYBLUE (-7225 3525);
FORCEPROP 2 LAST CDS_LIB pure_quanta
J 0
(-7275 3725);
PAINT MONO (-7275 3725);
DISPLAY INVISIBLE (-7275 3725);
FORCEPROP 1 LAST PATH I44
J 0
(-7225 3875);
DISPLAY 0.978723 (-7225 3875);
PAINT WHITE (-7225 3875);
DISPLAY INVISIBLE (-7225 3875);
FORCEADD Q_CAP..1
(-6825 2300);
FORCEPROP 1 LAST LOCATION C2567
J 0
(-6775 2400);
DISPLAY 0.489362 (-6775 2400);
PAINT SKYBLUE (-6775 2400);
FORCEPROP 2 LAST $SEC 1
J 0
(-6775 2500);
DISPLAY 0.680851 (-6775 2500);
PAINT MONO (-6775 2500);
DISPLAY INVISIBLE (-6775 2500);
FORCEPROP 2 LAST CDS_SEC 1
J 0
(-6775 2500);
DISPLAY 1.021277 (-6775 2500);
DISPLAY INVISIBLE (-6775 2500);
FORCEPROP 1 LASTPIN (-6825 2400) $PN 1
J 0
(-6815 2380);
DISPLAY 0.489362 (-6815 2380);
FORCEPROP 1 LASTPIN (-6825 2200) $PN 2
J 0
(-6815 2180);
DISPLAY 0.489362 (-6815 2180);
FORCEPROP 1 LAST MATERIAL X6S
J 0
(-6775 2200);
DISPLAY 0.489362 (-6775 2200);
PAINT SKYBLUE (-6775 2200);
FORCEPROP 1 LAST TOLERANCE 20%
J 0
(-6775 2250);
DISPLAY 0.489362 (-6775 2250);
PAINT SKYBLUE (-6775 2250);
FORCEPROP 1 LAST VALUE 22UF
J 0
(-6775 2350);
DISPLAY 0.489362 (-6775 2350);
PAINT SKYBLUE (-6775 2350);
FORCEPROP 1 LAST PART_NUMBER CH622KMEB02
J 0
(-6775 2150);
DISPLAY 0.489362 (-6775 2150);
PAINT SKYBLUE (-6775 2150);
FORCEPROP 1 LAST VOLTAGE 4V
J 0
(-6775 2300);
DISPLAY 0.489362 (-6775 2300);
PAINT SKYBLUE (-6775 2300);
FORCEPROP 1 LAST PACK_TYPE C0402
J 0
(-6775 2100);
DISPLAY 0.489362 (-6775 2100);
PAINT SKYBLUE (-6775 2100);
FORCEPROP 2 LAST CDS_LIB pure_quanta
J 0
(-6825 2300);
PAINT MONO (-6825 2300);
DISPLAY INVISIBLE (-6825 2300);
FORCEPROP 1 LAST PATH I45
J 0
(-6775 2450);
DISPLAY 0.978723 (-6775 2450);
PAINT WHITE (-6775 2450);
DISPLAY INVISIBLE (-6775 2450);
FORCEADD Q_CAP..1
(-6825 3000);
FORCEPROP 1 LAST LOCATION C2566
J 0
(-6775 3100);
DISPLAY 0.489362 (-6775 3100);
PAINT SKYBLUE (-6775 3100);
FORCEPROP 2 LAST $SEC 1
J 0
(-6775 3200);
DISPLAY 0.680851 (-6775 3200);
PAINT MONO (-6775 3200);
DISPLAY INVISIBLE (-6775 3200);
FORCEPROP 2 LAST CDS_SEC 1
J 0
(-6775 3200);
DISPLAY 1.021277 (-6775 3200);
DISPLAY INVISIBLE (-6775 3200);
FORCEPROP 1 LASTPIN (-6825 3100) $PN 1
J 0
(-6815 3080);
DISPLAY 0.489362 (-6815 3080);
FORCEPROP 1 LASTPIN (-6825 2900) $PN 2
J 0
(-6815 2880);
DISPLAY 0.489362 (-6815 2880);
FORCEPROP 1 LAST MATERIAL X6S
J 0
(-6775 2900);
DISPLAY 0.489362 (-6775 2900);
PAINT SKYBLUE (-6775 2900);
FORCEPROP 1 LAST TOLERANCE 20%
J 0
(-6775 2950);
DISPLAY 0.489362 (-6775 2950);
PAINT SKYBLUE (-6775 2950);
FORCEPROP 1 LAST VALUE 22UF
J 0
(-6775 3050);
DISPLAY 0.489362 (-6775 3050);
PAINT SKYBLUE (-6775 3050);
FORCEPROP 1 LAST PART_NUMBER CH622KMEB02
J 0
(-6775 2850);
DISPLAY 0.489362 (-6775 2850);
PAINT SKYBLUE (-6775 2850);
FORCEPROP 1 LAST VOLTAGE 4V
J 0
(-6775 3000);
DISPLAY 0.489362 (-6775 3000);
PAINT SKYBLUE (-6775 3000);
FORCEPROP 1 LAST PACK_TYPE C0402
J 0
(-6775 2800);
DISPLAY 0.489362 (-6775 2800);
PAINT SKYBLUE (-6775 2800);
FORCEPROP 2 LAST CDS_LIB pure_quanta
J 0
(-6825 3000);
PAINT MONO (-6825 3000);
DISPLAY INVISIBLE (-6825 3000);
FORCEPROP 1 LAST PATH I46
J 0
(-6775 3150);
DISPLAY 0.978723 (-6775 3150);
PAINT WHITE (-6775 3150);
DISPLAY INVISIBLE (-6775 3150);
FORCEADD Q_CAP..1
(-6375 2300);
FORCEPROP 1 LAST LOCATION C2574
J 0
(-6325 2400);
DISPLAY 0.489362 (-6325 2400);
PAINT SKYBLUE (-6325 2400);
FORCEPROP 2 LAST $SEC 1
J 0
(-6325 2500);
DISPLAY 0.680851 (-6325 2500);
PAINT MONO (-6325 2500);
DISPLAY INVISIBLE (-6325 2500);
FORCEPROP 2 LAST CDS_SEC 1
J 0
(-6325 2500);
DISPLAY 1.021277 (-6325 2500);
DISPLAY INVISIBLE (-6325 2500);
FORCEPROP 1 LASTPIN (-6375 2400) $PN 1
J 0
(-6365 2380);
DISPLAY 0.489362 (-6365 2380);
FORCEPROP 1 LASTPIN (-6375 2200) $PN 2
J 0
(-6365 2180);
DISPLAY 0.489362 (-6365 2180);
FORCEPROP 1 LAST MATERIAL X6S
J 0
(-6325 2200);
DISPLAY 0.489362 (-6325 2200);
PAINT SKYBLUE (-6325 2200);
FORCEPROP 1 LAST TOLERANCE 20%
J 0
(-6325 2250);
DISPLAY 0.489362 (-6325 2250);
PAINT SKYBLUE (-6325 2250);
FORCEPROP 1 LAST VALUE 22UF
J 0
(-6325 2350);
DISPLAY 0.489362 (-6325 2350);
PAINT SKYBLUE (-6325 2350);
FORCEPROP 1 LAST PART_NUMBER CH622KMEB02
J 0
(-6325 2150);
DISPLAY 0.489362 (-6325 2150);
PAINT SKYBLUE (-6325 2150);
FORCEPROP 1 LAST VOLTAGE 4V
J 0
(-6325 2300);
DISPLAY 0.489362 (-6325 2300);
PAINT SKYBLUE (-6325 2300);
FORCEPROP 1 LAST PACK_TYPE C0402
J 0
(-6325 2100);
DISPLAY 0.489362 (-6325 2100);
PAINT SKYBLUE (-6325 2100);
FORCEPROP 2 LAST CDS_LIB pure_quanta
J 0
(-6375 2300);
PAINT MONO (-6375 2300);
DISPLAY INVISIBLE (-6375 2300);
FORCEPROP 1 LAST PATH I47
J 0
(-6325 2450);
DISPLAY 0.978723 (-6325 2450);
PAINT WHITE (-6325 2450);
DISPLAY INVISIBLE (-6325 2450);
FORCEADD Q_CAP..1
(-6375 3000);
FORCEPROP 1 LAST LOCATION C2573
J 0
(-6325 3100);
DISPLAY 0.489362 (-6325 3100);
PAINT SKYBLUE (-6325 3100);
FORCEPROP 2 LAST $SEC 1
J 0
(-6325 3200);
DISPLAY 0.680851 (-6325 3200);
PAINT MONO (-6325 3200);
DISPLAY INVISIBLE (-6325 3200);
FORCEPROP 2 LAST CDS_SEC 1
J 0
(-6325 3200);
DISPLAY 1.021277 (-6325 3200);
DISPLAY INVISIBLE (-6325 3200);
FORCEPROP 1 LASTPIN (-6375 3100) $PN 1
J 0
(-6365 3080);
DISPLAY 0.489362 (-6365 3080);
FORCEPROP 1 LASTPIN (-6375 2900) $PN 2
J 0
(-6365 2880);
DISPLAY 0.489362 (-6365 2880);
FORCEPROP 1 LAST MATERIAL X6S
J 0
(-6325 2900);
DISPLAY 0.489362 (-6325 2900);
PAINT SKYBLUE (-6325 2900);
FORCEPROP 1 LAST TOLERANCE 20%
J 0
(-6325 2950);
DISPLAY 0.489362 (-6325 2950);
PAINT SKYBLUE (-6325 2950);
FORCEPROP 1 LAST VALUE 22UF
J 0
(-6325 3050);
DISPLAY 0.489362 (-6325 3050);
PAINT SKYBLUE (-6325 3050);
FORCEPROP 1 LAST PART_NUMBER CH622KMEB02
J 0
(-6325 2850);
DISPLAY 0.489362 (-6325 2850);
PAINT SKYBLUE (-6325 2850);
FORCEPROP 1 LAST VOLTAGE 4V
J 0
(-6325 3000);
DISPLAY 0.489362 (-6325 3000);
PAINT SKYBLUE (-6325 3000);
FORCEPROP 1 LAST PACK_TYPE C0402
J 0
(-6325 2800);
DISPLAY 0.489362 (-6325 2800);
PAINT SKYBLUE (-6325 2800);
FORCEPROP 2 LAST CDS_LIB pure_quanta
J 0
(-6375 3000);
PAINT MONO (-6375 3000);
DISPLAY INVISIBLE (-6375 3000);
FORCEPROP 1 LAST PATH I48
J 0
(-6325 3150);
DISPLAY 0.978723 (-6325 3150);
PAINT WHITE (-6325 3150);
DISPLAY INVISIBLE (-6325 3150);
FORCEADD Q_CAP..1
(-6825 3725);
FORCEPROP 1 LAST LOCATION C2565
J 0
(-6775 3825);
DISPLAY 0.489362 (-6775 3825);
PAINT SKYBLUE (-6775 3825);
FORCEPROP 2 LAST $SEC 1
J 0
(-6775 3925);
DISPLAY 0.680851 (-6775 3925);
PAINT MONO (-6775 3925);
DISPLAY INVISIBLE (-6775 3925);
FORCEPROP 2 LAST CDS_SEC 1
J 0
(-6775 3925);
DISPLAY 1.021277 (-6775 3925);
DISPLAY INVISIBLE (-6775 3925);
FORCEPROP 1 LASTPIN (-6825 3825) $PN 1
J 0
(-6815 3805);
DISPLAY 0.489362 (-6815 3805);
FORCEPROP 1 LASTPIN (-6825 3625) $PN 2
J 0
(-6815 3605);
DISPLAY 0.489362 (-6815 3605);
FORCEPROP 1 LAST MATERIAL X6S
J 0
(-6775 3625);
DISPLAY 0.489362 (-6775 3625);
PAINT SKYBLUE (-6775 3625);
FORCEPROP 1 LAST TOLERANCE 20%
J 0
(-6775 3675);
DISPLAY 0.489362 (-6775 3675);
PAINT SKYBLUE (-6775 3675);
FORCEPROP 1 LAST VALUE 22UF
J 0
(-6775 3775);
DISPLAY 0.489362 (-6775 3775);
PAINT SKYBLUE (-6775 3775);
FORCEPROP 1 LAST PART_NUMBER CH622KMEB02
J 0
(-6775 3575);
DISPLAY 0.489362 (-6775 3575);
PAINT SKYBLUE (-6775 3575);
FORCEPROP 1 LAST VOLTAGE 4V
J 0
(-6775 3725);
DISPLAY 0.489362 (-6775 3725);
PAINT SKYBLUE (-6775 3725);
FORCEPROP 1 LAST PACK_TYPE C0402
J 0
(-6775 3525);
DISPLAY 0.489362 (-6775 3525);
PAINT SKYBLUE (-6775 3525);
FORCEPROP 2 LAST CDS_LIB pure_quanta
J 0
(-6825 3725);
PAINT MONO (-6825 3725);
DISPLAY INVISIBLE (-6825 3725);
FORCEPROP 1 LAST PATH I49
J 0
(-6775 3875);
DISPLAY 0.978723 (-6775 3875);
PAINT WHITE (-6775 3875);
DISPLAY INVISIBLE (-6775 3875);
FORCEADD UNIVERSAL_POWER..1
(-9075 1850);
FORCEPROP 3 LASTPIN (-9075 1800) SIG_NAME PVDDCR_SOC_P0\g
J 0
(-9065 1810);
DISPLAY 0.659574 (-9065 1810);
PAINT MONO (-9065 1810);
DISPLAY INVISIBLE (-9065 1810);
FORCEPROP 1 LAST HDL_POWER PVDDCR_SOC_P0
J 1
(-9075 1900);
DISPLAY 0.489362 (-9075 1900);
PAINT GREEN (-9075 1900);
FORCEPROP 2 LAST CDS_LIB pure_quanta_power
J 0
(-9075 1850);
DISPLAY INVISIBLE (-9075 1850);
FORCEPROP 1 LAST PATH I5
J 0
(-9025 1875);
DISPLAY 0.872340 (-9025 1875);
PAINT AQUA (-9025 1875);
DISPLAY INVISIBLE (-9025 1875);
FORCEADD Q_CAP..1
(-6375 3725);
FORCEPROP 1 LAST LOCATION C2572
J 0
(-6325 3825);
DISPLAY 0.489362 (-6325 3825);
PAINT SKYBLUE (-6325 3825);
FORCEPROP 2 LAST $SEC 1
J 0
(-6325 3925);
DISPLAY 0.680851 (-6325 3925);
PAINT MONO (-6325 3925);
DISPLAY INVISIBLE (-6325 3925);
FORCEPROP 2 LAST CDS_SEC 1
J 0
(-6325 3925);
DISPLAY 1.021277 (-6325 3925);
DISPLAY INVISIBLE (-6325 3925);
FORCEPROP 1 LASTPIN (-6375 3825) $PN 1
J 0
(-6365 3805);
DISPLAY 0.489362 (-6365 3805);
FORCEPROP 1 LASTPIN (-6375 3625) $PN 2
J 0
(-6365 3605);
DISPLAY 0.489362 (-6365 3605);
FORCEPROP 1 LAST MATERIAL X6S
J 0
(-6325 3625);
DISPLAY 0.489362 (-6325 3625);
PAINT SKYBLUE (-6325 3625);
FORCEPROP 1 LAST TOLERANCE 20%
J 0
(-6325 3675);
DISPLAY 0.489362 (-6325 3675);
PAINT SKYBLUE (-6325 3675);
FORCEPROP 1 LAST VALUE 22UF
J 0
(-6325 3775);
DISPLAY 0.489362 (-6325 3775);
PAINT SKYBLUE (-6325 3775);
FORCEPROP 1 LAST PART_NUMBER CH622KMEB02
J 0
(-6325 3575);
DISPLAY 0.489362 (-6325 3575);
PAINT SKYBLUE (-6325 3575);
FORCEPROP 1 LAST VOLTAGE 4V
J 0
(-6325 3725);
DISPLAY 0.489362 (-6325 3725);
PAINT SKYBLUE (-6325 3725);
FORCEPROP 1 LAST PACK_TYPE C0402
J 0
(-6325 3525);
DISPLAY 0.489362 (-6325 3525);
PAINT SKYBLUE (-6325 3525);
FORCEPROP 2 LAST CDS_LIB pure_quanta
J 0
(-6375 3725);
PAINT MONO (-6375 3725);
DISPLAY INVISIBLE (-6375 3725);
FORCEPROP 1 LAST PATH I50
J 0
(-6325 3875);
DISPLAY 0.978723 (-6325 3875);
PAINT WHITE (-6325 3875);
DISPLAY INVISIBLE (-6325 3875);
FORCEADD Q_CAP..1
(-5925 1575);
FORCEPROP 1 LAST LOCATION C2582
J 0
(-5875 1675);
DISPLAY 0.489362 (-5875 1675);
PAINT SKYBLUE (-5875 1675);
FORCEPROP 2 LAST $SEC 1
J 0
(-5875 1775);
DISPLAY 0.680851 (-5875 1775);
PAINT MONO (-5875 1775);
DISPLAY INVISIBLE (-5875 1775);
FORCEPROP 2 LAST CDS_SEC 1
J 0
(-5875 1775);
DISPLAY 1.021277 (-5875 1775);
DISPLAY INVISIBLE (-5875 1775);
FORCEPROP 1 LASTPIN (-5925 1675) $PN 1
J 0
(-5915 1655);
DISPLAY 0.489362 (-5915 1655);
FORCEPROP 1 LASTPIN (-5925 1475) $PN 2
J 0
(-5915 1455);
DISPLAY 0.489362 (-5915 1455);
FORCEPROP 1 LAST MATERIAL X6S
J 0
(-5875 1475);
DISPLAY 0.489362 (-5875 1475);
PAINT SKYBLUE (-5875 1475);
FORCEPROP 1 LAST TOLERANCE 20%
J 0
(-5875 1525);
DISPLAY 0.489362 (-5875 1525);
PAINT SKYBLUE (-5875 1525);
FORCEPROP 1 LAST VALUE 22UF
J 0
(-5875 1625);
DISPLAY 0.489362 (-5875 1625);
PAINT SKYBLUE (-5875 1625);
FORCEPROP 1 LAST PART_NUMBER CH622KMEB02
J 0
(-5875 1425);
DISPLAY 0.489362 (-5875 1425);
PAINT SKYBLUE (-5875 1425);
FORCEPROP 1 LAST VOLTAGE 4V
J 0
(-5875 1575);
DISPLAY 0.489362 (-5875 1575);
PAINT SKYBLUE (-5875 1575);
FORCEPROP 1 LAST PACK_TYPE C0402
J 0
(-5875 1375);
DISPLAY 0.489362 (-5875 1375);
PAINT SKYBLUE (-5875 1375);
FORCEPROP 2 LAST CDS_LIB pure_quanta
J 0
(-5925 1575);
PAINT MONO (-5925 1575);
DISPLAY INVISIBLE (-5925 1575);
FORCEPROP 1 LAST PATH I51
J 0
(-5875 1725);
DISPLAY 0.978723 (-5875 1725);
PAINT WHITE (-5875 1725);
DISPLAY INVISIBLE (-5875 1725);
FORCEADD Q_CAP..1
(-5475 1575);
FORCEPROP 1 LAST LOCATION C2589
J 0
(-5425 1675);
DISPLAY 0.489362 (-5425 1675);
PAINT SKYBLUE (-5425 1675);
FORCEPROP 2 LAST $SEC 1
J 0
(-5425 1775);
DISPLAY 0.680851 (-5425 1775);
PAINT MONO (-5425 1775);
DISPLAY INVISIBLE (-5425 1775);
FORCEPROP 2 LAST CDS_SEC 1
J 0
(-5425 1775);
DISPLAY 1.021277 (-5425 1775);
DISPLAY INVISIBLE (-5425 1775);
FORCEPROP 1 LASTPIN (-5475 1675) $PN 1
J 0
(-5465 1655);
DISPLAY 0.489362 (-5465 1655);
FORCEPROP 1 LASTPIN (-5475 1475) $PN 2
J 0
(-5465 1455);
DISPLAY 0.489362 (-5465 1455);
FORCEPROP 1 LAST MATERIAL X6S
J 0
(-5425 1475);
DISPLAY 0.489362 (-5425 1475);
PAINT SKYBLUE (-5425 1475);
FORCEPROP 1 LAST TOLERANCE 20%
J 0
(-5425 1525);
DISPLAY 0.489362 (-5425 1525);
PAINT SKYBLUE (-5425 1525);
FORCEPROP 1 LAST VALUE 22UF
J 0
(-5425 1625);
DISPLAY 0.489362 (-5425 1625);
PAINT SKYBLUE (-5425 1625);
FORCEPROP 1 LAST PART_NUMBER CH622KMEB02
J 0
(-5425 1425);
DISPLAY 0.489362 (-5425 1425);
PAINT SKYBLUE (-5425 1425);
FORCEPROP 1 LAST VOLTAGE 4V
J 0
(-5425 1575);
DISPLAY 0.489362 (-5425 1575);
PAINT SKYBLUE (-5425 1575);
FORCEPROP 1 LAST PACK_TYPE C0402
J 0
(-5425 1375);
DISPLAY 0.489362 (-5425 1375);
PAINT SKYBLUE (-5425 1375);
FORCEPROP 2 LAST CDS_LIB pure_quanta
J 0
(-5475 1575);
PAINT MONO (-5475 1575);
DISPLAY INVISIBLE (-5475 1575);
FORCEPROP 1 LAST PATH I52
J 0
(-5425 1725);
DISPLAY 0.978723 (-5425 1725);
PAINT WHITE (-5425 1725);
DISPLAY INVISIBLE (-5425 1725);
FORCEADD Q_CAP..1
(-4500 800);
FORCEPROP 1 LAST LOCATION C3932
J 0
(-4450 900);
DISPLAY 0.489362 (-4450 900);
PAINT SKYBLUE (-4450 900);
FORCEPROP 2 LAST $SEC 1
J 0
(-4450 1000);
DISPLAY 0.680851 (-4450 1000);
PAINT MONO (-4450 1000);
DISPLAY INVISIBLE (-4450 1000);
FORCEPROP 2 LAST CDS_SEC 1
J 0
(-4450 1000);
DISPLAY 1.021277 (-4450 1000);
DISPLAY INVISIBLE (-4450 1000);
FORCEPROP 1 LASTPIN (-4500 900) $PN 1
J 0
(-4490 880);
DISPLAY 0.489362 (-4490 880);
FORCEPROP 1 LASTPIN (-4500 700) $PN 2
J 0
(-4490 680);
DISPLAY 0.489362 (-4490 680);
FORCEPROP 1 LAST MATERIAL X6S
J 0
(-4450 700);
DISPLAY 0.489362 (-4450 700);
PAINT SKYBLUE (-4450 700);
FORCEPROP 1 LAST TOLERANCE 20%
J 0
(-4450 750);
DISPLAY 0.489362 (-4450 750);
PAINT SKYBLUE (-4450 750);
FORCEPROP 1 LAST VALUE 22UF
J 0
(-4450 850);
DISPLAY 0.489362 (-4450 850);
PAINT SKYBLUE (-4450 850);
FORCEPROP 1 LAST PART_NUMBER CH622KMEB02
J 0
(-4450 650);
DISPLAY 0.489362 (-4450 650);
PAINT SKYBLUE (-4450 650);
FORCEPROP 1 LAST VOLTAGE 4V
J 0
(-4450 800);
DISPLAY 0.489362 (-4450 800);
PAINT SKYBLUE (-4450 800);
FORCEPROP 1 LAST PACK_TYPE C0402
J 0
(-4450 600);
DISPLAY 0.489362 (-4450 600);
PAINT SKYBLUE (-4450 600);
FORCEPROP 2 LAST CDS_LIB pure_quanta
J 0
(-4500 800);
PAINT MONO (-4500 800);
DISPLAY INVISIBLE (-4500 800);
FORCEPROP 1 LAST PATH I53
J 0
(-4450 950);
DISPLAY 0.978723 (-4450 950);
PAINT WHITE (-4450 950);
DISPLAY INVISIBLE (-4450 950);
FORCEADD UNIVERSAL_POWER..1
(-4500 1075);
FORCEPROP 3 LASTPIN (-4500 1025) SIG_NAME PVDD11_S3_P0\g
J 0
(-4490 1035);
DISPLAY 0.659574 (-4490 1035);
PAINT MONO (-4490 1035);
DISPLAY INVISIBLE (-4490 1035);
FORCEPROP 1 LAST HDL_POWER PVDD11_S3_P0
J 1
(-4500 1125);
DISPLAY 0.489362 (-4500 1125);
PAINT GREEN (-4500 1125);
FORCEPROP 2 LAST CDS_LIB pure_quanta_power
J 0
(-4500 1075);
DISPLAY INVISIBLE (-4500 1075);
FORCEPROP 1 LAST PATH I54
J 0
(-4450 1100);
DISPLAY 0.872340 (-4450 1100);
PAINT AQUA (-4450 1100);
DISPLAY INVISIBLE (-4450 1100);
FORCEADD UNIVERSAL_GND..1
(-5075 1200);
FORCEPROP 3 LASTPIN (-5075 1250) SIG_NAME GND\g
J 0
(-5065 1260);
DISPLAY 0.659574 (-5065 1260);
PAINT MONO (-5065 1260);
DISPLAY INVISIBLE (-5065 1260);
FORCEPROP 2 LAST CDS_LIB pure_quanta_power
J 0
(-5075 1200);
PAINT MONO (-5075 1200);
DISPLAY INVISIBLE (-5075 1200);
FORCEPROP 1 LAST PATH I55
J 0
(-5000 1200);
DISPLAY 0.872340 (-5000 1200);
PAINT AQUA (-5000 1200);
DISPLAY INVISIBLE (-5000 1200);
FORCEPROP 1 LAST HDL_POWER GND
J 1
(-5050 1125);
DISPLAY 0.872340 (-5050 1125);
PAINT GREEN (-5050 1125);
DISPLAY INVISIBLE (-5050 1125);
FORCEADD Q_CAP..1
(-5075 1575);
FORCEPROP 1 LAST LOCATION C2596
J 0
(-5025 1675);
DISPLAY 0.489362 (-5025 1675);
PAINT SKYBLUE (-5025 1675);
FORCEPROP 2 LAST $SEC 1
J 0
(-5025 1775);
DISPLAY 0.680851 (-5025 1775);
PAINT MONO (-5025 1775);
DISPLAY INVISIBLE (-5025 1775);
FORCEPROP 2 LAST CDS_SEC 1
J 0
(-5025 1775);
DISPLAY 1.021277 (-5025 1775);
DISPLAY INVISIBLE (-5025 1775);
FORCEPROP 1 LASTPIN (-5075 1675) $PN 1
J 0
(-5065 1655);
DISPLAY 0.489362 (-5065 1655);
FORCEPROP 1 LASTPIN (-5075 1475) $PN 2
J 0
(-5065 1455);
DISPLAY 0.489362 (-5065 1455);
FORCEPROP 1 LAST MATERIAL X6S
J 0
(-5025 1475);
DISPLAY 0.489362 (-5025 1475);
PAINT SKYBLUE (-5025 1475);
FORCEPROP 1 LAST TOLERANCE 20%
J 0
(-5025 1525);
DISPLAY 0.489362 (-5025 1525);
PAINT SKYBLUE (-5025 1525);
FORCEPROP 1 LAST VALUE 22UF
J 0
(-5025 1625);
DISPLAY 0.489362 (-5025 1625);
PAINT SKYBLUE (-5025 1625);
FORCEPROP 1 LAST PART_NUMBER CH622KMEB02
J 0
(-5025 1425);
DISPLAY 0.489362 (-5025 1425);
PAINT SKYBLUE (-5025 1425);
FORCEPROP 1 LAST VOLTAGE 4V
J 0
(-5025 1575);
DISPLAY 0.489362 (-5025 1575);
PAINT SKYBLUE (-5025 1575);
FORCEPROP 1 LAST PACK_TYPE C0402
J 0
(-5025 1375);
DISPLAY 0.489362 (-5025 1375);
PAINT SKYBLUE (-5025 1375);
FORCEPROP 2 LAST CDS_LIB pure_quanta
J 0
(-5075 1575);
PAINT MONO (-5075 1575);
DISPLAY INVISIBLE (-5075 1575);
FORCEPROP 1 LAST PATH I56
J 0
(-5025 1725);
DISPLAY 0.978723 (-5025 1725);
PAINT WHITE (-5025 1725);
DISPLAY INVISIBLE (-5025 1725);
FORCEADD UNIVERSAL_GND..1
(-5075 1925);
FORCEPROP 3 LASTPIN (-5075 1975) SIG_NAME GND\g
J 0
(-5065 1985);
DISPLAY 0.659574 (-5065 1985);
PAINT MONO (-5065 1985);
DISPLAY INVISIBLE (-5065 1985);
FORCEPROP 2 LAST CDS_LIB pure_quanta_power
J 0
(-5075 1925);
PAINT MONO (-5075 1925);
DISPLAY INVISIBLE (-5075 1925);
FORCEPROP 1 LAST PATH I57
J 0
(-5000 1925);
DISPLAY 0.872340 (-5000 1925);
PAINT AQUA (-5000 1925);
DISPLAY INVISIBLE (-5000 1925);
FORCEPROP 1 LAST HDL_POWER GND
J 1
(-5050 1850);
DISPLAY 0.872340 (-5050 1850);
PAINT GREEN (-5050 1850);
DISPLAY INVISIBLE (-5050 1850);
FORCEADD Q_CAP..1
(-4500 1400);
FORCEPROP 1 LAST LOCATION C2603
J 0
(-4450 1500);
DISPLAY 0.489362 (-4450 1500);
PAINT SKYBLUE (-4450 1500);
FORCEPROP 2 LAST $SEC 1
J 0
(-4450 1600);
DISPLAY 0.680851 (-4450 1600);
PAINT MONO (-4450 1600);
DISPLAY INVISIBLE (-4450 1600);
FORCEPROP 2 LAST CDS_SEC 1
J 0
(-4450 1600);
DISPLAY 1.021277 (-4450 1600);
DISPLAY INVISIBLE (-4450 1600);
FORCEPROP 1 LASTPIN (-4500 1500) $PN 1
J 0
(-4490 1480);
DISPLAY 0.489362 (-4490 1480);
FORCEPROP 1 LASTPIN (-4500 1300) $PN 2
J 0
(-4490 1280);
DISPLAY 0.489362 (-4490 1280);
FORCEPROP 1 LAST MATERIAL X6S
J 0
(-4450 1300);
DISPLAY 0.489362 (-4450 1300);
PAINT SKYBLUE (-4450 1300);
FORCEPROP 1 LAST TOLERANCE 20%
J 0
(-4450 1350);
DISPLAY 0.489362 (-4450 1350);
PAINT SKYBLUE (-4450 1350);
FORCEPROP 1 LAST VALUE 22UF
J 0
(-4450 1450);
DISPLAY 0.489362 (-4450 1450);
PAINT SKYBLUE (-4450 1450);
FORCEPROP 1 LAST PART_NUMBER CH622KMEB02
J 0
(-4450 1250);
DISPLAY 0.489362 (-4450 1250);
PAINT SKYBLUE (-4450 1250);
FORCEPROP 1 LAST VOLTAGE 4V
J 0
(-4450 1400);
DISPLAY 0.489362 (-4450 1400);
PAINT SKYBLUE (-4450 1400);
FORCEPROP 1 LAST PACK_TYPE C0402
J 0
(-4450 1200);
DISPLAY 0.489362 (-4450 1200);
PAINT SKYBLUE (-4450 1200);
FORCEPROP 2 LAST CDS_LIB pure_quanta
J 0
(-4500 1400);
PAINT MONO (-4500 1400);
DISPLAY INVISIBLE (-4500 1400);
FORCEPROP 1 LAST PATH I58
J 0
(-4450 1550);
DISPLAY 0.978723 (-4450 1550);
PAINT WHITE (-4450 1550);
DISPLAY INVISIBLE (-4450 1550);
FORCEADD UNIVERSAL_POWER..1
(-4500 1675);
FORCEPROP 3 LASTPIN (-4500 1625) SIG_NAME PVDD11_S3_P0\g
J 0
(-4490 1635);
DISPLAY 0.659574 (-4490 1635);
PAINT MONO (-4490 1635);
DISPLAY INVISIBLE (-4490 1635);
FORCEPROP 1 LAST HDL_POWER PVDD11_S3_P0
J 1
(-4500 1725);
DISPLAY 0.489362 (-4500 1725);
PAINT GREEN (-4500 1725);
FORCEPROP 2 LAST CDS_LIB pure_quanta_power
J 0
(-4500 1675);
DISPLAY INVISIBLE (-4500 1675);
FORCEPROP 1 LAST PATH I59
J 0
(-4450 1700);
DISPLAY 0.872340 (-4450 1700);
PAINT AQUA (-4450 1700);
DISPLAY INVISIBLE (-4450 1700);
FORCEADD Q_CAP..1
(-8625 1575);
FORCEPROP 1 LAST LOCATION C2540
J 0
(-8575 1675);
DISPLAY 0.489362 (-8575 1675);
PAINT SKYBLUE (-8575 1675);
FORCEPROP 2 LAST $SEC 1
J 0
(-8575 1775);
DISPLAY 0.680851 (-8575 1775);
PAINT MONO (-8575 1775);
DISPLAY INVISIBLE (-8575 1775);
FORCEPROP 2 LAST CDS_SEC 1
J 0
(-8575 1775);
DISPLAY 1.021277 (-8575 1775);
DISPLAY INVISIBLE (-8575 1775);
FORCEPROP 1 LASTPIN (-8625 1675) $PN 1
J 0
(-8615 1655);
DISPLAY 0.489362 (-8615 1655);
FORCEPROP 1 LASTPIN (-8625 1475) $PN 2
J 0
(-8615 1455);
DISPLAY 0.489362 (-8615 1455);
FORCEPROP 1 LAST MATERIAL X6S
J 0
(-8575 1475);
DISPLAY 0.489362 (-8575 1475);
PAINT SKYBLUE (-8575 1475);
FORCEPROP 1 LAST TOLERANCE 20%
J 0
(-8575 1525);
DISPLAY 0.489362 (-8575 1525);
PAINT SKYBLUE (-8575 1525);
FORCEPROP 1 LAST VALUE 22UF
J 0
(-8575 1625);
DISPLAY 0.489362 (-8575 1625);
PAINT SKYBLUE (-8575 1625);
FORCEPROP 1 LAST PART_NUMBER CH622KMEB02
J 0
(-8575 1425);
DISPLAY 0.489362 (-8575 1425);
PAINT SKYBLUE (-8575 1425);
FORCEPROP 1 LAST VOLTAGE 4V
J 0
(-8575 1575);
DISPLAY 0.489362 (-8575 1575);
PAINT SKYBLUE (-8575 1575);
FORCEPROP 1 LAST PACK_TYPE C0402
J 0
(-8575 1375);
DISPLAY 0.489362 (-8575 1375);
PAINT SKYBLUE (-8575 1375);
FORCEPROP 2 LAST CDS_LIB pure_quanta
J 0
(-8625 1575);
PAINT MONO (-8625 1575);
DISPLAY INVISIBLE (-8625 1575);
FORCEPROP 1 LAST PATH I6
J 0
(-8575 1725);
DISPLAY 0.978723 (-8575 1725);
PAINT WHITE (-8575 1725);
DISPLAY INVISIBLE (-8575 1725);
FORCEADD Q_CAP..1
(-4500 2000);
FORCEPROP 1 LAST LOCATION C2602
J 0
(-4450 2100);
DISPLAY 0.489362 (-4450 2100);
PAINT SKYBLUE (-4450 2100);
FORCEPROP 2 LAST $SEC 1
J 0
(-4450 2200);
DISPLAY 0.680851 (-4450 2200);
PAINT MONO (-4450 2200);
DISPLAY INVISIBLE (-4450 2200);
FORCEPROP 2 LAST CDS_SEC 1
J 0
(-4450 2200);
DISPLAY 1.021277 (-4450 2200);
DISPLAY INVISIBLE (-4450 2200);
FORCEPROP 1 LASTPIN (-4500 2100) $PN 1
J 0
(-4490 2080);
DISPLAY 0.489362 (-4490 2080);
FORCEPROP 1 LASTPIN (-4500 1900) $PN 2
J 0
(-4490 1880);
DISPLAY 0.489362 (-4490 1880);
FORCEPROP 1 LAST MATERIAL X6S
J 0
(-4450 1900);
DISPLAY 0.489362 (-4450 1900);
PAINT SKYBLUE (-4450 1900);
FORCEPROP 1 LAST TOLERANCE 20%
J 0
(-4450 1950);
DISPLAY 0.489362 (-4450 1950);
PAINT SKYBLUE (-4450 1950);
FORCEPROP 1 LAST VALUE 22UF
J 0
(-4450 2050);
DISPLAY 0.489362 (-4450 2050);
PAINT SKYBLUE (-4450 2050);
FORCEPROP 1 LAST PART_NUMBER CH622KMEB02
J 0
(-4450 1850);
DISPLAY 0.489362 (-4450 1850);
PAINT SKYBLUE (-4450 1850);
FORCEPROP 1 LAST VOLTAGE 4V
J 0
(-4450 2000);
DISPLAY 0.489362 (-4450 2000);
PAINT SKYBLUE (-4450 2000);
FORCEPROP 1 LAST PACK_TYPE C0402
J 0
(-4450 1800);
DISPLAY 0.489362 (-4450 1800);
PAINT SKYBLUE (-4450 1800);
FORCEPROP 2 LAST CDS_LIB pure_quanta
J 0
(-4500 2000);
PAINT MONO (-4500 2000);
DISPLAY INVISIBLE (-4500 2000);
FORCEPROP 1 LAST PATH I60
J 0
(-4450 2150);
DISPLAY 0.978723 (-4450 2150);
PAINT WHITE (-4450 2150);
DISPLAY INVISIBLE (-4450 2150);
FORCEADD Q_CAP..1
(-5925 2300);
FORCEPROP 1 LAST LOCATION C2581
J 0
(-5875 2400);
DISPLAY 0.489362 (-5875 2400);
PAINT SKYBLUE (-5875 2400);
FORCEPROP 2 LAST $SEC 1
J 0
(-5875 2500);
DISPLAY 0.680851 (-5875 2500);
PAINT MONO (-5875 2500);
DISPLAY INVISIBLE (-5875 2500);
FORCEPROP 2 LAST CDS_SEC 1
J 0
(-5875 2500);
DISPLAY 1.021277 (-5875 2500);
DISPLAY INVISIBLE (-5875 2500);
FORCEPROP 1 LASTPIN (-5925 2400) $PN 1
J 0
(-5915 2380);
DISPLAY 0.489362 (-5915 2380);
FORCEPROP 1 LASTPIN (-5925 2200) $PN 2
J 0
(-5915 2180);
DISPLAY 0.489362 (-5915 2180);
FORCEPROP 1 LAST MATERIAL X6S
J 0
(-5875 2200);
DISPLAY 0.489362 (-5875 2200);
PAINT SKYBLUE (-5875 2200);
FORCEPROP 1 LAST TOLERANCE 20%
J 0
(-5875 2250);
DISPLAY 0.489362 (-5875 2250);
PAINT SKYBLUE (-5875 2250);
FORCEPROP 1 LAST VALUE 22UF
J 0
(-5875 2350);
DISPLAY 0.489362 (-5875 2350);
PAINT SKYBLUE (-5875 2350);
FORCEPROP 1 LAST PART_NUMBER CH622KMEB02
J 0
(-5875 2150);
DISPLAY 0.489362 (-5875 2150);
PAINT SKYBLUE (-5875 2150);
FORCEPROP 1 LAST VOLTAGE 4V
J 0
(-5875 2300);
DISPLAY 0.489362 (-5875 2300);
PAINT SKYBLUE (-5875 2300);
FORCEPROP 1 LAST PACK_TYPE C0402
J 0
(-5875 2100);
DISPLAY 0.489362 (-5875 2100);
PAINT SKYBLUE (-5875 2100);
FORCEPROP 2 LAST CDS_LIB pure_quanta
J 0
(-5925 2300);
PAINT MONO (-5925 2300);
DISPLAY INVISIBLE (-5925 2300);
FORCEPROP 1 LAST PATH I61
J 0
(-5875 2450);
DISPLAY 0.978723 (-5875 2450);
PAINT WHITE (-5875 2450);
DISPLAY INVISIBLE (-5875 2450);
FORCEADD Q_CAP..1
(-5925 3000);
FORCEPROP 1 LAST LOCATION C2580
J 0
(-5875 3100);
DISPLAY 0.489362 (-5875 3100);
PAINT SKYBLUE (-5875 3100);
FORCEPROP 2 LAST $SEC 1
J 0
(-5875 3200);
DISPLAY 0.680851 (-5875 3200);
PAINT MONO (-5875 3200);
DISPLAY INVISIBLE (-5875 3200);
FORCEPROP 2 LAST CDS_SEC 1
J 0
(-5875 3200);
DISPLAY 1.021277 (-5875 3200);
DISPLAY INVISIBLE (-5875 3200);
FORCEPROP 1 LASTPIN (-5925 3100) $PN 1
J 0
(-5915 3080);
DISPLAY 0.489362 (-5915 3080);
FORCEPROP 1 LASTPIN (-5925 2900) $PN 2
J 0
(-5915 2880);
DISPLAY 0.489362 (-5915 2880);
FORCEPROP 1 LAST MATERIAL X6S
J 0
(-5875 2900);
DISPLAY 0.489362 (-5875 2900);
PAINT SKYBLUE (-5875 2900);
FORCEPROP 1 LAST TOLERANCE 20%
J 0
(-5875 2950);
DISPLAY 0.489362 (-5875 2950);
PAINT SKYBLUE (-5875 2950);
FORCEPROP 1 LAST VALUE 22UF
J 0
(-5875 3050);
DISPLAY 0.489362 (-5875 3050);
PAINT SKYBLUE (-5875 3050);
FORCEPROP 1 LAST PART_NUMBER CH622KMEB02
J 0
(-5875 2850);
DISPLAY 0.489362 (-5875 2850);
PAINT SKYBLUE (-5875 2850);
FORCEPROP 1 LAST VOLTAGE 4V
J 0
(-5875 3000);
DISPLAY 0.489362 (-5875 3000);
PAINT SKYBLUE (-5875 3000);
FORCEPROP 1 LAST PACK_TYPE C0402
J 0
(-5875 2800);
DISPLAY 0.489362 (-5875 2800);
PAINT SKYBLUE (-5875 2800);
FORCEPROP 2 LAST CDS_LIB pure_quanta
J 0
(-5925 3000);
PAINT MONO (-5925 3000);
DISPLAY INVISIBLE (-5925 3000);
FORCEPROP 1 LAST PATH I62
J 0
(-5875 3150);
DISPLAY 0.978723 (-5875 3150);
PAINT WHITE (-5875 3150);
DISPLAY INVISIBLE (-5875 3150);
FORCEADD Q_CAP..1
(-5475 2300);
FORCEPROP 1 LAST LOCATION C2588
J 0
(-5425 2400);
DISPLAY 0.489362 (-5425 2400);
PAINT SKYBLUE (-5425 2400);
FORCEPROP 2 LAST $SEC 1
J 0
(-5425 2500);
DISPLAY 0.680851 (-5425 2500);
PAINT MONO (-5425 2500);
DISPLAY INVISIBLE (-5425 2500);
FORCEPROP 2 LAST CDS_SEC 1
J 0
(-5425 2500);
DISPLAY 1.021277 (-5425 2500);
DISPLAY INVISIBLE (-5425 2500);
FORCEPROP 1 LASTPIN (-5475 2400) $PN 1
J 0
(-5465 2380);
DISPLAY 0.489362 (-5465 2380);
FORCEPROP 1 LASTPIN (-5475 2200) $PN 2
J 0
(-5465 2180);
DISPLAY 0.489362 (-5465 2180);
FORCEPROP 1 LAST MATERIAL X6S
J 0
(-5425 2200);
DISPLAY 0.489362 (-5425 2200);
PAINT SKYBLUE (-5425 2200);
FORCEPROP 1 LAST TOLERANCE 20%
J 0
(-5425 2250);
DISPLAY 0.489362 (-5425 2250);
PAINT SKYBLUE (-5425 2250);
FORCEPROP 1 LAST VALUE 22UF
J 0
(-5425 2350);
DISPLAY 0.489362 (-5425 2350);
PAINT SKYBLUE (-5425 2350);
FORCEPROP 1 LAST PART_NUMBER CH622KMEB02
J 0
(-5425 2150);
DISPLAY 0.489362 (-5425 2150);
PAINT SKYBLUE (-5425 2150);
FORCEPROP 1 LAST VOLTAGE 4V
J 0
(-5425 2300);
DISPLAY 0.489362 (-5425 2300);
PAINT SKYBLUE (-5425 2300);
FORCEPROP 1 LAST PACK_TYPE C0402
J 0
(-5425 2100);
DISPLAY 0.489362 (-5425 2100);
PAINT SKYBLUE (-5425 2100);
FORCEPROP 2 LAST CDS_LIB pure_quanta
J 0
(-5475 2300);
PAINT MONO (-5475 2300);
DISPLAY INVISIBLE (-5475 2300);
FORCEPROP 1 LAST PATH I63
J 0
(-5425 2450);
DISPLAY 0.978723 (-5425 2450);
PAINT WHITE (-5425 2450);
DISPLAY INVISIBLE (-5425 2450);
FORCEADD Q_CAP..1
(-5475 3000);
FORCEPROP 1 LAST LOCATION C2587
J 0
(-5425 3100);
DISPLAY 0.489362 (-5425 3100);
PAINT SKYBLUE (-5425 3100);
FORCEPROP 2 LAST $SEC 1
J 0
(-5425 3200);
DISPLAY 0.680851 (-5425 3200);
PAINT MONO (-5425 3200);
DISPLAY INVISIBLE (-5425 3200);
FORCEPROP 2 LAST CDS_SEC 1
J 0
(-5425 3200);
DISPLAY 1.021277 (-5425 3200);
DISPLAY INVISIBLE (-5425 3200);
FORCEPROP 1 LASTPIN (-5475 3100) $PN 1
J 0
(-5465 3080);
DISPLAY 0.489362 (-5465 3080);
FORCEPROP 1 LASTPIN (-5475 2900) $PN 2
J 0
(-5465 2880);
DISPLAY 0.489362 (-5465 2880);
FORCEPROP 1 LAST MATERIAL X6S
J 0
(-5425 2900);
DISPLAY 0.489362 (-5425 2900);
PAINT SKYBLUE (-5425 2900);
FORCEPROP 1 LAST TOLERANCE 20%
J 0
(-5425 2950);
DISPLAY 0.489362 (-5425 2950);
PAINT SKYBLUE (-5425 2950);
FORCEPROP 1 LAST VALUE 22UF
J 0
(-5425 3050);
DISPLAY 0.489362 (-5425 3050);
PAINT SKYBLUE (-5425 3050);
FORCEPROP 1 LAST PART_NUMBER CH622KMEB02
J 0
(-5425 2850);
DISPLAY 0.489362 (-5425 2850);
PAINT SKYBLUE (-5425 2850);
FORCEPROP 1 LAST VOLTAGE 4V
J 0
(-5425 3000);
DISPLAY 0.489362 (-5425 3000);
PAINT SKYBLUE (-5425 3000);
FORCEPROP 1 LAST PACK_TYPE C0402
J 0
(-5425 2800);
DISPLAY 0.489362 (-5425 2800);
PAINT SKYBLUE (-5425 2800);
FORCEPROP 2 LAST CDS_LIB pure_quanta
J 0
(-5475 3000);
PAINT MONO (-5475 3000);
DISPLAY INVISIBLE (-5475 3000);
FORCEPROP 1 LAST PATH I64
J 0
(-5425 3150);
DISPLAY 0.978723 (-5425 3150);
PAINT WHITE (-5425 3150);
DISPLAY INVISIBLE (-5425 3150);
FORCEADD Q_CAP..1
(-5925 3725);
FORCEPROP 1 LAST LOCATION C2579
J 0
(-5875 3825);
DISPLAY 0.489362 (-5875 3825);
PAINT SKYBLUE (-5875 3825);
FORCEPROP 2 LAST $SEC 1
J 0
(-5875 3925);
DISPLAY 0.680851 (-5875 3925);
PAINT MONO (-5875 3925);
DISPLAY INVISIBLE (-5875 3925);
FORCEPROP 2 LAST CDS_SEC 1
J 0
(-5875 3925);
DISPLAY 1.021277 (-5875 3925);
DISPLAY INVISIBLE (-5875 3925);
FORCEPROP 1 LASTPIN (-5925 3825) $PN 1
J 0
(-5915 3805);
DISPLAY 0.489362 (-5915 3805);
FORCEPROP 1 LASTPIN (-5925 3625) $PN 2
J 0
(-5915 3605);
DISPLAY 0.489362 (-5915 3605);
FORCEPROP 1 LAST MATERIAL X6S
J 0
(-5875 3625);
DISPLAY 0.489362 (-5875 3625);
PAINT SKYBLUE (-5875 3625);
FORCEPROP 1 LAST TOLERANCE 20%
J 0
(-5875 3675);
DISPLAY 0.489362 (-5875 3675);
PAINT SKYBLUE (-5875 3675);
FORCEPROP 1 LAST VALUE 22UF
J 0
(-5875 3775);
DISPLAY 0.489362 (-5875 3775);
PAINT SKYBLUE (-5875 3775);
FORCEPROP 1 LAST PART_NUMBER CH622KMEB02
J 0
(-5875 3575);
DISPLAY 0.489362 (-5875 3575);
PAINT SKYBLUE (-5875 3575);
FORCEPROP 1 LAST VOLTAGE 4V
J 0
(-5875 3725);
DISPLAY 0.489362 (-5875 3725);
PAINT SKYBLUE (-5875 3725);
FORCEPROP 1 LAST PACK_TYPE C0402
J 0
(-5875 3525);
DISPLAY 0.489362 (-5875 3525);
PAINT SKYBLUE (-5875 3525);
FORCEPROP 2 LAST CDS_LIB pure_quanta
J 0
(-5925 3725);
PAINT MONO (-5925 3725);
DISPLAY INVISIBLE (-5925 3725);
FORCEPROP 1 LAST PATH I65
J 0
(-5875 3875);
DISPLAY 0.978723 (-5875 3875);
PAINT WHITE (-5875 3875);
DISPLAY INVISIBLE (-5875 3875);
FORCEADD Q_CAP..1
(-5475 3725);
FORCEPROP 1 LAST LOCATION C2586
J 0
(-5425 3825);
DISPLAY 0.489362 (-5425 3825);
PAINT SKYBLUE (-5425 3825);
FORCEPROP 2 LAST $SEC 1
J 0
(-5425 3925);
DISPLAY 0.680851 (-5425 3925);
PAINT MONO (-5425 3925);
DISPLAY INVISIBLE (-5425 3925);
FORCEPROP 2 LAST CDS_SEC 1
J 0
(-5425 3925);
DISPLAY 1.021277 (-5425 3925);
DISPLAY INVISIBLE (-5425 3925);
FORCEPROP 1 LASTPIN (-5475 3825) $PN 1
J 0
(-5465 3805);
DISPLAY 0.489362 (-5465 3805);
FORCEPROP 1 LASTPIN (-5475 3625) $PN 2
J 0
(-5465 3605);
DISPLAY 0.489362 (-5465 3605);
FORCEPROP 1 LAST MATERIAL X6S
J 0
(-5425 3625);
DISPLAY 0.489362 (-5425 3625);
PAINT SKYBLUE (-5425 3625);
FORCEPROP 1 LAST TOLERANCE 20%
J 0
(-5425 3675);
DISPLAY 0.489362 (-5425 3675);
PAINT SKYBLUE (-5425 3675);
FORCEPROP 1 LAST VALUE 22UF
J 0
(-5425 3775);
DISPLAY 0.489362 (-5425 3775);
PAINT SKYBLUE (-5425 3775);
FORCEPROP 1 LAST PART_NUMBER CH622KMEB02
J 0
(-5425 3575);
DISPLAY 0.489362 (-5425 3575);
PAINT SKYBLUE (-5425 3575);
FORCEPROP 1 LAST VOLTAGE 4V
J 0
(-5425 3725);
DISPLAY 0.489362 (-5425 3725);
PAINT SKYBLUE (-5425 3725);
FORCEPROP 1 LAST PACK_TYPE C0402
J 0
(-5425 3525);
DISPLAY 0.489362 (-5425 3525);
PAINT SKYBLUE (-5425 3525);
FORCEPROP 2 LAST CDS_LIB pure_quanta
J 0
(-5475 3725);
PAINT MONO (-5475 3725);
DISPLAY INVISIBLE (-5475 3725);
FORCEPROP 1 LAST PATH I66
J 0
(-5425 3875);
DISPLAY 0.978723 (-5425 3875);
PAINT WHITE (-5425 3875);
DISPLAY INVISIBLE (-5425 3875);
FORCEADD Q_CAP..1
(-5075 2300);
FORCEPROP 1 LAST LOCATION C2595
J 0
(-5025 2400);
DISPLAY 0.489362 (-5025 2400);
PAINT SKYBLUE (-5025 2400);
FORCEPROP 2 LAST $SEC 1
J 0
(-5025 2500);
DISPLAY 0.680851 (-5025 2500);
PAINT MONO (-5025 2500);
DISPLAY INVISIBLE (-5025 2500);
FORCEPROP 2 LAST CDS_SEC 1
J 0
(-5025 2500);
DISPLAY 1.021277 (-5025 2500);
DISPLAY INVISIBLE (-5025 2500);
FORCEPROP 1 LASTPIN (-5075 2400) $PN 1
J 0
(-5065 2380);
DISPLAY 0.489362 (-5065 2380);
FORCEPROP 1 LASTPIN (-5075 2200) $PN 2
J 0
(-5065 2180);
DISPLAY 0.489362 (-5065 2180);
FORCEPROP 1 LAST MATERIAL X6S
J 0
(-5025 2200);
DISPLAY 0.489362 (-5025 2200);
PAINT SKYBLUE (-5025 2200);
FORCEPROP 1 LAST TOLERANCE 20%
J 0
(-5025 2250);
DISPLAY 0.489362 (-5025 2250);
PAINT SKYBLUE (-5025 2250);
FORCEPROP 1 LAST VALUE 22UF
J 0
(-5025 2350);
DISPLAY 0.489362 (-5025 2350);
PAINT SKYBLUE (-5025 2350);
FORCEPROP 1 LAST PART_NUMBER CH622KMEB02
J 0
(-5025 2150);
DISPLAY 0.489362 (-5025 2150);
PAINT SKYBLUE (-5025 2150);
FORCEPROP 1 LAST VOLTAGE 4V
J 0
(-5025 2300);
DISPLAY 0.489362 (-5025 2300);
PAINT SKYBLUE (-5025 2300);
FORCEPROP 1 LAST PACK_TYPE C0402
J 0
(-5025 2100);
DISPLAY 0.489362 (-5025 2100);
PAINT SKYBLUE (-5025 2100);
FORCEPROP 2 LAST CDS_LIB pure_quanta
J 0
(-5075 2300);
PAINT MONO (-5075 2300);
DISPLAY INVISIBLE (-5075 2300);
FORCEPROP 1 LAST PATH I67
J 0
(-5025 2450);
DISPLAY 0.978723 (-5025 2450);
PAINT WHITE (-5025 2450);
DISPLAY INVISIBLE (-5025 2450);
FORCEADD UNIVERSAL_GND..1
(-5075 2625);
FORCEPROP 3 LASTPIN (-5075 2675) SIG_NAME GND\g
J 0
(-5065 2685);
DISPLAY 0.659574 (-5065 2685);
PAINT MONO (-5065 2685);
DISPLAY INVISIBLE (-5065 2685);
FORCEPROP 2 LAST CDS_LIB pure_quanta_power
J 0
(-5075 2625);
PAINT MONO (-5075 2625);
DISPLAY INVISIBLE (-5075 2625);
FORCEPROP 1 LAST PATH I68
J 0
(-5000 2625);
DISPLAY 0.872340 (-5000 2625);
PAINT AQUA (-5000 2625);
DISPLAY INVISIBLE (-5000 2625);
FORCEPROP 1 LAST HDL_POWER GND
J 1
(-5050 2550);
DISPLAY 0.872340 (-5050 2550);
PAINT GREEN (-5050 2550);
DISPLAY INVISIBLE (-5050 2550);
FORCEADD Q_CAP..1
(-5075 3000);
FORCEPROP 1 LAST LOCATION C2594
J 0
(-5025 3100);
DISPLAY 0.489362 (-5025 3100);
PAINT SKYBLUE (-5025 3100);
FORCEPROP 2 LAST $SEC 1
J 0
(-5025 3200);
DISPLAY 0.680851 (-5025 3200);
PAINT MONO (-5025 3200);
DISPLAY INVISIBLE (-5025 3200);
FORCEPROP 2 LAST CDS_SEC 1
J 0
(-5025 3200);
DISPLAY 1.021277 (-5025 3200);
DISPLAY INVISIBLE (-5025 3200);
FORCEPROP 1 LASTPIN (-5075 3100) $PN 1
J 0
(-5065 3080);
DISPLAY 0.489362 (-5065 3080);
FORCEPROP 1 LASTPIN (-5075 2900) $PN 2
J 0
(-5065 2880);
DISPLAY 0.489362 (-5065 2880);
FORCEPROP 1 LAST MATERIAL X6S
J 0
(-5025 2900);
DISPLAY 0.489362 (-5025 2900);
PAINT SKYBLUE (-5025 2900);
FORCEPROP 1 LAST TOLERANCE 20%
J 0
(-5025 2950);
DISPLAY 0.489362 (-5025 2950);
PAINT SKYBLUE (-5025 2950);
FORCEPROP 1 LAST VALUE 22UF
J 0
(-5025 3050);
DISPLAY 0.489362 (-5025 3050);
PAINT SKYBLUE (-5025 3050);
FORCEPROP 1 LAST PART_NUMBER CH622KMEB02
J 0
(-5025 2850);
DISPLAY 0.489362 (-5025 2850);
PAINT SKYBLUE (-5025 2850);
FORCEPROP 1 LAST VOLTAGE 4V
J 0
(-5025 3000);
DISPLAY 0.489362 (-5025 3000);
PAINT SKYBLUE (-5025 3000);
FORCEPROP 1 LAST PACK_TYPE C0402
J 0
(-5025 2800);
DISPLAY 0.489362 (-5025 2800);
PAINT SKYBLUE (-5025 2800);
FORCEPROP 2 LAST CDS_LIB pure_quanta
J 0
(-5075 3000);
PAINT MONO (-5075 3000);
DISPLAY INVISIBLE (-5075 3000);
FORCEPROP 1 LAST PATH I69
J 0
(-5025 3150);
DISPLAY 0.978723 (-5025 3150);
PAINT WHITE (-5025 3150);
DISPLAY INVISIBLE (-5025 3150);
FORCEADD Q_CAP..1
(-9075 2300);
FORCEPROP 1 LAST LOCATION C2532
J 0
(-9025 2400);
DISPLAY 0.489362 (-9025 2400);
PAINT SKYBLUE (-9025 2400);
FORCEPROP 2 LAST $SEC 1
J 0
(-9025 2500);
DISPLAY 0.680851 (-9025 2500);
PAINT MONO (-9025 2500);
DISPLAY INVISIBLE (-9025 2500);
FORCEPROP 2 LAST CDS_SEC 1
J 0
(-9025 2500);
DISPLAY 1.021277 (-9025 2500);
DISPLAY INVISIBLE (-9025 2500);
FORCEPROP 1 LASTPIN (-9075 2400) $PN 1
J 0
(-9065 2380);
DISPLAY 0.489362 (-9065 2380);
FORCEPROP 1 LASTPIN (-9075 2200) $PN 2
J 0
(-9065 2180);
DISPLAY 0.489362 (-9065 2180);
FORCEPROP 1 LAST MATERIAL X6S
J 0
(-9025 2200);
DISPLAY 0.489362 (-9025 2200);
PAINT SKYBLUE (-9025 2200);
FORCEPROP 1 LAST TOLERANCE 20%
J 0
(-9025 2250);
DISPLAY 0.489362 (-9025 2250);
PAINT SKYBLUE (-9025 2250);
FORCEPROP 1 LAST VALUE 22UF
J 0
(-9025 2350);
DISPLAY 0.489362 (-9025 2350);
PAINT SKYBLUE (-9025 2350);
FORCEPROP 1 LAST PART_NUMBER CH622KMEB02
J 0
(-9025 2150);
DISPLAY 0.489362 (-9025 2150);
PAINT SKYBLUE (-9025 2150);
FORCEPROP 1 LAST VOLTAGE 4V
J 0
(-9025 2300);
DISPLAY 0.489362 (-9025 2300);
PAINT SKYBLUE (-9025 2300);
FORCEPROP 1 LAST PACK_TYPE C0402
J 0
(-9025 2100);
DISPLAY 0.489362 (-9025 2100);
PAINT SKYBLUE (-9025 2100);
FORCEPROP 2 LAST CDS_LIB pure_quanta
J 0
(-9075 2300);
PAINT MONO (-9075 2300);
DISPLAY INVISIBLE (-9075 2300);
FORCEPROP 1 LAST PATH I7
J 0
(-9025 2450);
DISPLAY 0.978723 (-9025 2450);
PAINT WHITE (-9025 2450);
DISPLAY INVISIBLE (-9025 2450);
FORCEADD UNIVERSAL_POWER..1
(-4500 2275);
FORCEPROP 3 LASTPIN (-4500 2225) SIG_NAME PVDD11_S3_P0\g
J 0
(-4490 2235);
DISPLAY 0.659574 (-4490 2235);
PAINT MONO (-4490 2235);
DISPLAY INVISIBLE (-4490 2235);
FORCEPROP 1 LAST HDL_POWER PVDD11_S3_P0
J 1
(-4500 2325);
DISPLAY 0.489362 (-4500 2325);
PAINT GREEN (-4500 2325);
FORCEPROP 2 LAST CDS_LIB pure_quanta_power
J 0
(-4500 2275);
DISPLAY INVISIBLE (-4500 2275);
FORCEPROP 1 LAST PATH I70
J 0
(-4450 2300);
DISPLAY 0.872340 (-4450 2300);
PAINT AQUA (-4450 2300);
DISPLAY INVISIBLE (-4450 2300);
FORCEADD Q_CAP..1
(-4500 2625);
FORCEPROP 1 LAST LOCATION C2601
J 0
(-4450 2725);
DISPLAY 0.489362 (-4450 2725);
PAINT SKYBLUE (-4450 2725);
FORCEPROP 2 LAST $SEC 1
J 0
(-4450 2825);
DISPLAY 0.680851 (-4450 2825);
PAINT MONO (-4450 2825);
DISPLAY INVISIBLE (-4450 2825);
FORCEPROP 2 LAST CDS_SEC 1
J 0
(-4450 2825);
DISPLAY 1.021277 (-4450 2825);
DISPLAY INVISIBLE (-4450 2825);
FORCEPROP 1 LASTPIN (-4500 2725) $PN 1
J 0
(-4490 2705);
DISPLAY 0.489362 (-4490 2705);
FORCEPROP 1 LASTPIN (-4500 2525) $PN 2
J 0
(-4490 2505);
DISPLAY 0.489362 (-4490 2505);
FORCEPROP 1 LAST MATERIAL X6S
J 0
(-4450 2525);
DISPLAY 0.489362 (-4450 2525);
PAINT SKYBLUE (-4450 2525);
FORCEPROP 1 LAST TOLERANCE 20%
J 0
(-4450 2575);
DISPLAY 0.489362 (-4450 2575);
PAINT SKYBLUE (-4450 2575);
FORCEPROP 1 LAST VALUE 22UF
J 0
(-4450 2675);
DISPLAY 0.489362 (-4450 2675);
PAINT SKYBLUE (-4450 2675);
FORCEPROP 1 LAST PART_NUMBER CH622KMEB02
J 0
(-4450 2475);
DISPLAY 0.489362 (-4450 2475);
PAINT SKYBLUE (-4450 2475);
FORCEPROP 1 LAST VOLTAGE 4V
J 0
(-4450 2625);
DISPLAY 0.489362 (-4450 2625);
PAINT SKYBLUE (-4450 2625);
FORCEPROP 1 LAST PACK_TYPE C0402
J 0
(-4450 2425);
DISPLAY 0.489362 (-4450 2425);
PAINT SKYBLUE (-4450 2425);
FORCEPROP 2 LAST CDS_LIB pure_quanta
J 0
(-4500 2625);
PAINT MONO (-4500 2625);
DISPLAY INVISIBLE (-4500 2625);
FORCEPROP 1 LAST PATH I71
J 0
(-4450 2775);
DISPLAY 0.978723 (-4450 2775);
PAINT WHITE (-4450 2775);
DISPLAY INVISIBLE (-4450 2775);
FORCEADD UNIVERSAL_POWER..1
(-4500 2900);
FORCEPROP 3 LASTPIN (-4500 2850) SIG_NAME PVDD11_S3_P0\g
J 0
(-4490 2860);
DISPLAY 0.659574 (-4490 2860);
PAINT MONO (-4490 2860);
DISPLAY INVISIBLE (-4490 2860);
FORCEPROP 1 LAST HDL_POWER PVDD11_S3_P0
J 1
(-4500 2950);
DISPLAY 0.489362 (-4500 2950);
PAINT GREEN (-4500 2950);
FORCEPROP 2 LAST CDS_LIB pure_quanta_power
J 0
(-4500 2900);
DISPLAY INVISIBLE (-4500 2900);
FORCEPROP 1 LAST PATH I72
J 0
(-4450 2925);
DISPLAY 0.872340 (-4450 2925);
PAINT AQUA (-4450 2925);
DISPLAY INVISIBLE (-4450 2925);
FORCEADD UNIVERSAL_GND..1
(-5075 3350);
FORCEPROP 3 LASTPIN (-5075 3400) SIG_NAME GND\g
J 0
(-5065 3410);
DISPLAY 0.659574 (-5065 3410);
PAINT MONO (-5065 3410);
DISPLAY INVISIBLE (-5065 3410);
FORCEPROP 2 LAST CDS_LIB pure_quanta_power
J 0
(-5075 3350);
PAINT MONO (-5075 3350);
DISPLAY INVISIBLE (-5075 3350);
FORCEPROP 1 LAST PATH I73
J 0
(-5000 3350);
DISPLAY 0.872340 (-5000 3350);
PAINT AQUA (-5000 3350);
DISPLAY INVISIBLE (-5000 3350);
FORCEPROP 1 LAST HDL_POWER GND
J 1
(-5050 3275);
DISPLAY 0.872340 (-5050 3275);
PAINT GREEN (-5050 3275);
DISPLAY INVISIBLE (-5050 3275);
FORCEADD Q_CAP..1
(-5075 3725);
FORCEPROP 1 LAST LOCATION C2593
J 0
(-5025 3825);
DISPLAY 0.489362 (-5025 3825);
PAINT SKYBLUE (-5025 3825);
FORCEPROP 2 LAST $SEC 1
J 0
(-5025 3925);
DISPLAY 0.680851 (-5025 3925);
PAINT MONO (-5025 3925);
DISPLAY INVISIBLE (-5025 3925);
FORCEPROP 2 LAST CDS_SEC 1
J 0
(-5025 3925);
DISPLAY 1.021277 (-5025 3925);
DISPLAY INVISIBLE (-5025 3925);
FORCEPROP 1 LASTPIN (-5075 3825) $PN 1
J 0
(-5065 3805);
DISPLAY 0.489362 (-5065 3805);
FORCEPROP 1 LASTPIN (-5075 3625) $PN 2
J 0
(-5065 3605);
DISPLAY 0.489362 (-5065 3605);
FORCEPROP 1 LAST MATERIAL X6S
J 0
(-5025 3625);
DISPLAY 0.489362 (-5025 3625);
PAINT SKYBLUE (-5025 3625);
FORCEPROP 1 LAST TOLERANCE 20%
J 0
(-5025 3675);
DISPLAY 0.489362 (-5025 3675);
PAINT SKYBLUE (-5025 3675);
FORCEPROP 1 LAST VALUE 22UF
J 0
(-5025 3775);
DISPLAY 0.489362 (-5025 3775);
PAINT SKYBLUE (-5025 3775);
FORCEPROP 1 LAST PART_NUMBER CH622KMEB02
J 0
(-5025 3575);
DISPLAY 0.489362 (-5025 3575);
PAINT SKYBLUE (-5025 3575);
FORCEPROP 1 LAST VOLTAGE 4V
J 0
(-5025 3725);
DISPLAY 0.489362 (-5025 3725);
PAINT SKYBLUE (-5025 3725);
FORCEPROP 1 LAST PACK_TYPE C0402
J 0
(-5025 3525);
DISPLAY 0.489362 (-5025 3525);
PAINT SKYBLUE (-5025 3525);
FORCEPROP 2 LAST CDS_LIB pure_quanta
J 0
(-5075 3725);
PAINT MONO (-5075 3725);
DISPLAY INVISIBLE (-5075 3725);
FORCEPROP 1 LAST PATH I74
J 0
(-5025 3875);
DISPLAY 0.978723 (-5025 3875);
PAINT WHITE (-5025 3875);
DISPLAY INVISIBLE (-5025 3875);
FORCEADD UNIVERSAL_GND..1
(-5100 4050);
FORCEPROP 3 LASTPIN (-5100 4100) SIG_NAME GND\g
J 0
(-5090 4110);
DISPLAY 0.659574 (-5090 4110);
PAINT MONO (-5090 4110);
DISPLAY INVISIBLE (-5090 4110);
FORCEPROP 2 LAST CDS_LIB pure_quanta_power
J 0
(-5100 4050);
PAINT MONO (-5100 4050);
DISPLAY INVISIBLE (-5100 4050);
FORCEPROP 1 LAST PATH I75
J 0
(-5025 4050);
DISPLAY 0.872340 (-5025 4050);
PAINT AQUA (-5025 4050);
DISPLAY INVISIBLE (-5025 4050);
FORCEPROP 1 LAST HDL_POWER GND
J 1
(-5075 3975);
DISPLAY 0.872340 (-5075 3975);
PAINT GREEN (-5075 3975);
DISPLAY INVISIBLE (-5075 3975);
FORCEADD Q_CAP..1
(-4500 3275);
FORCEPROP 1 LAST LOCATION C2600
J 0
(-4450 3375);
DISPLAY 0.489362 (-4450 3375);
PAINT SKYBLUE (-4450 3375);
FORCEPROP 2 LAST $SEC 1
J 0
(-4450 3475);
DISPLAY 0.680851 (-4450 3475);
PAINT MONO (-4450 3475);
DISPLAY INVISIBLE (-4450 3475);
FORCEPROP 2 LAST CDS_SEC 1
J 0
(-4450 3475);
DISPLAY 1.021277 (-4450 3475);
DISPLAY INVISIBLE (-4450 3475);
FORCEPROP 1 LASTPIN (-4500 3375) $PN 1
J 0
(-4490 3355);
DISPLAY 0.489362 (-4490 3355);
FORCEPROP 1 LASTPIN (-4500 3175) $PN 2
J 0
(-4490 3155);
DISPLAY 0.489362 (-4490 3155);
FORCEPROP 1 LAST MATERIAL X6S
J 0
(-4450 3175);
DISPLAY 0.489362 (-4450 3175);
PAINT SKYBLUE (-4450 3175);
FORCEPROP 1 LAST TOLERANCE 20%
J 0
(-4450 3225);
DISPLAY 0.489362 (-4450 3225);
PAINT SKYBLUE (-4450 3225);
FORCEPROP 1 LAST VALUE 22UF
J 0
(-4450 3325);
DISPLAY 0.489362 (-4450 3325);
PAINT SKYBLUE (-4450 3325);
FORCEPROP 1 LAST PART_NUMBER CH622KMEB02
J 0
(-4450 3125);
DISPLAY 0.489362 (-4450 3125);
PAINT SKYBLUE (-4450 3125);
FORCEPROP 1 LAST VOLTAGE 4V
J 0
(-4450 3275);
DISPLAY 0.489362 (-4450 3275);
PAINT SKYBLUE (-4450 3275);
FORCEPROP 1 LAST PACK_TYPE C0402
J 0
(-4450 3075);
DISPLAY 0.489362 (-4450 3075);
PAINT SKYBLUE (-4450 3075);
FORCEPROP 2 LAST CDS_LIB pure_quanta
J 0
(-4500 3275);
PAINT MONO (-4500 3275);
DISPLAY INVISIBLE (-4500 3275);
FORCEPROP 1 LAST PATH I76
J 0
(-4450 3425);
DISPLAY 0.978723 (-4450 3425);
PAINT WHITE (-4450 3425);
DISPLAY INVISIBLE (-4450 3425);
FORCEADD UNIVERSAL_POWER..1
(-4500 3550);
FORCEPROP 3 LASTPIN (-4500 3500) SIG_NAME PVDD11_S3_P0\g
J 0
(-4490 3510);
DISPLAY 0.659574 (-4490 3510);
PAINT MONO (-4490 3510);
DISPLAY INVISIBLE (-4490 3510);
FORCEPROP 1 LAST HDL_POWER PVDD11_S3_P0
J 1
(-4500 3600);
DISPLAY 0.489362 (-4500 3600);
PAINT GREEN (-4500 3600);
FORCEPROP 2 LAST CDS_LIB pure_quanta_power
J 0
(-4500 3550);
DISPLAY INVISIBLE (-4500 3550);
FORCEPROP 1 LAST PATH I77
J 0
(-4450 3575);
DISPLAY 0.872340 (-4450 3575);
PAINT AQUA (-4450 3575);
DISPLAY INVISIBLE (-4450 3575);
FORCEADD Q_CAP..1
(-8200 4425);
FORCEPROP 1 LAST LOCATION C2543
J 0
(-8150 4525);
DISPLAY 0.489362 (-8150 4525);
PAINT SKYBLUE (-8150 4525);
FORCEPROP 2 LAST $SEC 1
J 0
(-8150 4625);
DISPLAY 0.680851 (-8150 4625);
PAINT MONO (-8150 4625);
DISPLAY INVISIBLE (-8150 4625);
FORCEPROP 2 LAST CDS_SEC 1
J 0
(-8150 4625);
DISPLAY 1.021277 (-8150 4625);
DISPLAY INVISIBLE (-8150 4625);
FORCEPROP 1 LASTPIN (-8200 4525) $PN 1
J 0
(-8190 4505);
DISPLAY 0.489362 (-8190 4505);
FORCEPROP 1 LASTPIN (-8200 4325) $PN 2
J 0
(-8190 4305);
DISPLAY 0.489362 (-8190 4305);
FORCEPROP 1 LAST MATERIAL X6S
J 0
(-8150 4325);
DISPLAY 0.489362 (-8150 4325);
PAINT SKYBLUE (-8150 4325);
FORCEPROP 1 LAST TOLERANCE 20%
J 0
(-8150 4375);
DISPLAY 0.489362 (-8150 4375);
PAINT SKYBLUE (-8150 4375);
FORCEPROP 1 LAST VALUE 22UF
J 0
(-8150 4475);
DISPLAY 0.489362 (-8150 4475);
PAINT SKYBLUE (-8150 4475);
FORCEPROP 1 LAST PART_NUMBER CH622KMEB02
J 0
(-8150 4275);
DISPLAY 0.489362 (-8150 4275);
PAINT SKYBLUE (-8150 4275);
FORCEPROP 1 LAST VOLTAGE 4V
J 0
(-8150 4425);
DISPLAY 0.489362 (-8150 4425);
PAINT SKYBLUE (-8150 4425);
FORCEPROP 1 LAST PACK_TYPE C0402
J 0
(-8150 4225);
DISPLAY 0.489362 (-8150 4225);
PAINT SKYBLUE (-8150 4225);
FORCEPROP 2 LAST CDS_LIB pure_quanta
J 0
(-8200 4425);
PAINT MONO (-8200 4425);
DISPLAY INVISIBLE (-8200 4425);
FORCEPROP 1 LAST PATH I78
J 0
(-8150 4575);
DISPLAY 0.978723 (-8150 4575);
PAINT WHITE (-8150 4575);
DISPLAY INVISIBLE (-8150 4575);
FORCEADD Q_CAP..1
(-8200 5150);
FORCEPROP 1 LAST LOCATION C2542
J 0
(-8150 5250);
DISPLAY 0.489362 (-8150 5250);
PAINT SKYBLUE (-8150 5250);
FORCEPROP 2 LAST $SEC 1
J 0
(-8150 5350);
DISPLAY 0.680851 (-8150 5350);
PAINT MONO (-8150 5350);
DISPLAY INVISIBLE (-8150 5350);
FORCEPROP 2 LAST CDS_SEC 1
J 0
(-8150 5350);
DISPLAY 1.021277 (-8150 5350);
DISPLAY INVISIBLE (-8150 5350);
FORCEPROP 1 LASTPIN (-8200 5250) $PN 1
J 0
(-8190 5230);
DISPLAY 0.489362 (-8190 5230);
FORCEPROP 1 LASTPIN (-8200 5050) $PN 2
J 0
(-8190 5030);
DISPLAY 0.489362 (-8190 5030);
FORCEPROP 1 LAST MATERIAL X6S
J 0
(-8150 5050);
DISPLAY 0.489362 (-8150 5050);
PAINT SKYBLUE (-8150 5050);
FORCEPROP 1 LAST TOLERANCE 20%
J 0
(-8150 5100);
DISPLAY 0.489362 (-8150 5100);
PAINT SKYBLUE (-8150 5100);
FORCEPROP 1 LAST VALUE 22UF
J 0
(-8150 5200);
DISPLAY 0.489362 (-8150 5200);
PAINT SKYBLUE (-8150 5200);
FORCEPROP 1 LAST PART_NUMBER CH622KMEB02
J 0
(-8150 5000);
DISPLAY 0.489362 (-8150 5000);
PAINT SKYBLUE (-8150 5000);
FORCEPROP 1 LAST VOLTAGE 4V
J 0
(-8150 5150);
DISPLAY 0.489362 (-8150 5150);
PAINT SKYBLUE (-8150 5150);
FORCEPROP 1 LAST PACK_TYPE C0402
J 0
(-8150 4950);
DISPLAY 0.489362 (-8150 4950);
PAINT SKYBLUE (-8150 4950);
FORCEPROP 2 LAST CDS_LIB pure_quanta
J 0
(-8200 5150);
PAINT MONO (-8200 5150);
DISPLAY INVISIBLE (-8200 5150);
FORCEPROP 1 LAST PATH I79
J 0
(-8150 5300);
DISPLAY 0.978723 (-8150 5300);
PAINT WHITE (-8150 5300);
DISPLAY INVISIBLE (-8150 5300);
FORCEADD UNIVERSAL_POWER..1
(-9075 2575);
FORCEPROP 3 LASTPIN (-9075 2525) SIG_NAME PVDDCR_SOC_P0\g
J 0
(-9065 2535);
DISPLAY 0.659574 (-9065 2535);
PAINT MONO (-9065 2535);
DISPLAY INVISIBLE (-9065 2535);
FORCEPROP 1 LAST HDL_POWER PVDDCR_SOC_P0
J 1
(-9075 2625);
DISPLAY 0.489362 (-9075 2625);
PAINT GREEN (-9075 2625);
FORCEPROP 2 LAST CDS_LIB pure_quanta_power
J 0
(-9075 2575);
DISPLAY INVISIBLE (-9075 2575);
FORCEPROP 1 LAST PATH I8
J 0
(-9025 2600);
DISPLAY 0.872340 (-9025 2600);
PAINT AQUA (-9025 2600);
DISPLAY INVISIBLE (-9025 2600);
FORCEADD Q_CAP..1
(-7750 4425);
FORCEPROP 1 LAST LOCATION C2550
J 0
(-7700 4525);
DISPLAY 0.489362 (-7700 4525);
PAINT SKYBLUE (-7700 4525);
FORCEPROP 2 LAST $SEC 1
J 0
(-7700 4625);
DISPLAY 0.680851 (-7700 4625);
PAINT MONO (-7700 4625);
DISPLAY INVISIBLE (-7700 4625);
FORCEPROP 2 LAST CDS_SEC 1
J 0
(-7700 4625);
DISPLAY 1.021277 (-7700 4625);
DISPLAY INVISIBLE (-7700 4625);
FORCEPROP 1 LASTPIN (-7750 4525) $PN 1
J 0
(-7740 4505);
DISPLAY 0.489362 (-7740 4505);
FORCEPROP 1 LASTPIN (-7750 4325) $PN 2
J 0
(-7740 4305);
DISPLAY 0.489362 (-7740 4305);
FORCEPROP 1 LAST MATERIAL X6S
J 0
(-7700 4325);
DISPLAY 0.489362 (-7700 4325);
PAINT SKYBLUE (-7700 4325);
FORCEPROP 1 LAST TOLERANCE 20%
J 0
(-7700 4375);
DISPLAY 0.489362 (-7700 4375);
PAINT SKYBLUE (-7700 4375);
FORCEPROP 1 LAST VALUE 22UF
J 0
(-7700 4475);
DISPLAY 0.489362 (-7700 4475);
PAINT SKYBLUE (-7700 4475);
FORCEPROP 1 LAST PART_NUMBER CH622KMEB02
J 0
(-7700 4275);
DISPLAY 0.489362 (-7700 4275);
PAINT SKYBLUE (-7700 4275);
FORCEPROP 1 LAST VOLTAGE 4V
J 0
(-7700 4425);
DISPLAY 0.489362 (-7700 4425);
PAINT SKYBLUE (-7700 4425);
FORCEPROP 1 LAST PACK_TYPE C0402
J 0
(-7700 4225);
DISPLAY 0.489362 (-7700 4225);
PAINT SKYBLUE (-7700 4225);
FORCEPROP 2 LAST CDS_LIB pure_quanta
J 0
(-7750 4425);
PAINT MONO (-7750 4425);
DISPLAY INVISIBLE (-7750 4425);
FORCEPROP 1 LAST PATH I80
J 0
(-7700 4575);
DISPLAY 0.978723 (-7700 4575);
PAINT WHITE (-7700 4575);
DISPLAY INVISIBLE (-7700 4575);
FORCEADD Q_CAP..1
(-7750 5150);
FORCEPROP 1 LAST LOCATION C2549
J 0
(-7700 5250);
DISPLAY 0.489362 (-7700 5250);
PAINT SKYBLUE (-7700 5250);
FORCEPROP 2 LAST $SEC 1
J 0
(-7700 5350);
DISPLAY 0.680851 (-7700 5350);
PAINT MONO (-7700 5350);
DISPLAY INVISIBLE (-7700 5350);
FORCEPROP 2 LAST CDS_SEC 1
J 0
(-7700 5350);
DISPLAY 1.021277 (-7700 5350);
DISPLAY INVISIBLE (-7700 5350);
FORCEPROP 1 LASTPIN (-7750 5250) $PN 1
J 0
(-7740 5230);
DISPLAY 0.489362 (-7740 5230);
FORCEPROP 1 LASTPIN (-7750 5050) $PN 2
J 0
(-7740 5030);
DISPLAY 0.489362 (-7740 5030);
FORCEPROP 1 LAST MATERIAL X6S
J 0
(-7700 5050);
DISPLAY 0.489362 (-7700 5050);
PAINT SKYBLUE (-7700 5050);
FORCEPROP 1 LAST TOLERANCE 20%
J 0
(-7700 5100);
DISPLAY 0.489362 (-7700 5100);
PAINT SKYBLUE (-7700 5100);
FORCEPROP 1 LAST VALUE 22UF
J 0
(-7700 5200);
DISPLAY 0.489362 (-7700 5200);
PAINT SKYBLUE (-7700 5200);
FORCEPROP 1 LAST PART_NUMBER CH622KMEB02
J 0
(-7700 5000);
DISPLAY 0.489362 (-7700 5000);
PAINT SKYBLUE (-7700 5000);
FORCEPROP 1 LAST VOLTAGE 4V
J 0
(-7700 5150);
DISPLAY 0.489362 (-7700 5150);
PAINT SKYBLUE (-7700 5150);
FORCEPROP 1 LAST PACK_TYPE C0402
J 0
(-7700 4950);
DISPLAY 0.489362 (-7700 4950);
PAINT SKYBLUE (-7700 4950);
FORCEPROP 2 LAST CDS_LIB pure_quanta
J 0
(-7750 5150);
PAINT MONO (-7750 5150);
DISPLAY INVISIBLE (-7750 5150);
FORCEPROP 1 LAST PATH I81
J 0
(-7700 5300);
DISPLAY 0.978723 (-7700 5300);
PAINT WHITE (-7700 5300);
DISPLAY INVISIBLE (-7700 5300);
FORCEADD Q_CAP..1
(-7300 4425);
FORCEPROP 1 LAST LOCATION C2557
J 0
(-7250 4525);
DISPLAY 0.489362 (-7250 4525);
PAINT SKYBLUE (-7250 4525);
FORCEPROP 2 LAST $SEC 1
J 0
(-7250 4625);
DISPLAY 0.680851 (-7250 4625);
PAINT MONO (-7250 4625);
DISPLAY INVISIBLE (-7250 4625);
FORCEPROP 2 LAST CDS_SEC 1
J 0
(-7250 4625);
DISPLAY 1.021277 (-7250 4625);
DISPLAY INVISIBLE (-7250 4625);
FORCEPROP 1 LASTPIN (-7300 4525) $PN 1
J 0
(-7290 4505);
DISPLAY 0.489362 (-7290 4505);
FORCEPROP 1 LASTPIN (-7300 4325) $PN 2
J 0
(-7290 4305);
DISPLAY 0.489362 (-7290 4305);
FORCEPROP 1 LAST MATERIAL X6S
J 0
(-7250 4325);
DISPLAY 0.489362 (-7250 4325);
PAINT SKYBLUE (-7250 4325);
FORCEPROP 1 LAST TOLERANCE 20%
J 0
(-7250 4375);
DISPLAY 0.489362 (-7250 4375);
PAINT SKYBLUE (-7250 4375);
FORCEPROP 1 LAST VALUE 22UF
J 0
(-7250 4475);
DISPLAY 0.489362 (-7250 4475);
PAINT SKYBLUE (-7250 4475);
FORCEPROP 1 LAST PART_NUMBER CH622KMEB02
J 0
(-7250 4275);
DISPLAY 0.489362 (-7250 4275);
PAINT SKYBLUE (-7250 4275);
FORCEPROP 1 LAST VOLTAGE 4V
J 0
(-7250 4425);
DISPLAY 0.489362 (-7250 4425);
PAINT SKYBLUE (-7250 4425);
FORCEPROP 1 LAST PACK_TYPE C0402
J 0
(-7250 4225);
DISPLAY 0.489362 (-7250 4225);
PAINT SKYBLUE (-7250 4225);
FORCEPROP 2 LAST CDS_LIB pure_quanta
J 0
(-7300 4425);
PAINT MONO (-7300 4425);
DISPLAY INVISIBLE (-7300 4425);
FORCEPROP 1 LAST PATH I82
J 0
(-7250 4575);
DISPLAY 0.978723 (-7250 4575);
PAINT WHITE (-7250 4575);
DISPLAY INVISIBLE (-7250 4575);
FORCEADD Q_CAP..1
(-7300 5150);
FORCEPROP 1 LAST LOCATION C2556
J 0
(-7250 5250);
DISPLAY 0.489362 (-7250 5250);
PAINT SKYBLUE (-7250 5250);
FORCEPROP 2 LAST $SEC 1
J 0
(-7250 5350);
DISPLAY 0.680851 (-7250 5350);
PAINT MONO (-7250 5350);
DISPLAY INVISIBLE (-7250 5350);
FORCEPROP 2 LAST CDS_SEC 1
J 0
(-7250 5350);
DISPLAY 1.021277 (-7250 5350);
DISPLAY INVISIBLE (-7250 5350);
FORCEPROP 1 LASTPIN (-7300 5250) $PN 1
J 0
(-7290 5230);
DISPLAY 0.489362 (-7290 5230);
FORCEPROP 1 LASTPIN (-7300 5050) $PN 2
J 0
(-7290 5030);
DISPLAY 0.489362 (-7290 5030);
FORCEPROP 1 LAST MATERIAL X6S
J 0
(-7250 5050);
DISPLAY 0.489362 (-7250 5050);
PAINT SKYBLUE (-7250 5050);
FORCEPROP 1 LAST TOLERANCE 20%
J 0
(-7250 5100);
DISPLAY 0.489362 (-7250 5100);
PAINT SKYBLUE (-7250 5100);
FORCEPROP 1 LAST VALUE 22UF
J 0
(-7250 5200);
DISPLAY 0.489362 (-7250 5200);
PAINT SKYBLUE (-7250 5200);
FORCEPROP 1 LAST PART_NUMBER CH622KMEB02
J 0
(-7250 5000);
DISPLAY 0.489362 (-7250 5000);
PAINT SKYBLUE (-7250 5000);
FORCEPROP 1 LAST VOLTAGE 4V
J 0
(-7250 5150);
DISPLAY 0.489362 (-7250 5150);
PAINT SKYBLUE (-7250 5150);
FORCEPROP 1 LAST PACK_TYPE C0402
J 0
(-7250 4950);
DISPLAY 0.489362 (-7250 4950);
PAINT SKYBLUE (-7250 4950);
FORCEPROP 2 LAST CDS_LIB pure_quanta
J 0
(-7300 5150);
PAINT MONO (-7300 5150);
DISPLAY INVISIBLE (-7300 5150);
FORCEPROP 1 LAST PATH I83
J 0
(-7250 5300);
DISPLAY 0.978723 (-7250 5300);
PAINT WHITE (-7250 5300);
DISPLAY INVISIBLE (-7250 5300);
FORCEADD Q_CAP..1
(-8200 5900);
FORCEPROP 1 LAST LOCATION C2541
J 0
(-8150 6000);
DISPLAY 0.489362 (-8150 6000);
PAINT SKYBLUE (-8150 6000);
FORCEPROP 2 LAST $SEC 1
J 0
(-8150 6100);
DISPLAY 0.680851 (-8150 6100);
PAINT MONO (-8150 6100);
DISPLAY INVISIBLE (-8150 6100);
FORCEPROP 2 LAST CDS_SEC 1
J 0
(-8150 6100);
DISPLAY 1.021277 (-8150 6100);
DISPLAY INVISIBLE (-8150 6100);
FORCEPROP 1 LASTPIN (-8200 6000) $PN 1
J 0
(-8190 5980);
DISPLAY 0.489362 (-8190 5980);
FORCEPROP 1 LASTPIN (-8200 5800) $PN 2
J 0
(-8190 5780);
DISPLAY 0.489362 (-8190 5780);
FORCEPROP 1 LAST MATERIAL X6S
J 0
(-8150 5800);
DISPLAY 0.489362 (-8150 5800);
PAINT SKYBLUE (-8150 5800);
FORCEPROP 1 LAST TOLERANCE 20%
J 0
(-8150 5850);
DISPLAY 0.489362 (-8150 5850);
PAINT SKYBLUE (-8150 5850);
FORCEPROP 1 LAST VALUE 22UF
J 0
(-8150 5950);
DISPLAY 0.489362 (-8150 5950);
PAINT SKYBLUE (-8150 5950);
FORCEPROP 1 LAST PART_NUMBER CH622KMEB02
J 0
(-8150 5750);
DISPLAY 0.489362 (-8150 5750);
PAINT SKYBLUE (-8150 5750);
FORCEPROP 1 LAST VOLTAGE 4V
J 0
(-8150 5900);
DISPLAY 0.489362 (-8150 5900);
PAINT SKYBLUE (-8150 5900);
FORCEPROP 1 LAST PACK_TYPE C0402
J 0
(-8150 5700);
DISPLAY 0.489362 (-8150 5700);
PAINT SKYBLUE (-8150 5700);
FORCEPROP 2 LAST CDS_LIB pure_quanta
J 0
(-8200 5900);
PAINT MONO (-8200 5900);
DISPLAY INVISIBLE (-8200 5900);
FORCEPROP 1 LAST PATH I84
J 0
(-8150 6050);
DISPLAY 0.978723 (-8150 6050);
PAINT WHITE (-8150 6050);
DISPLAY INVISIBLE (-8150 6050);
FORCEADD Q_CAP..1
(-7750 5900);
FORCEPROP 1 LAST LOCATION C2548
J 0
(-7700 6000);
DISPLAY 0.489362 (-7700 6000);
PAINT SKYBLUE (-7700 6000);
FORCEPROP 2 LAST $SEC 1
J 0
(-7700 6100);
DISPLAY 0.680851 (-7700 6100);
PAINT MONO (-7700 6100);
DISPLAY INVISIBLE (-7700 6100);
FORCEPROP 2 LAST CDS_SEC 1
J 0
(-7700 6100);
DISPLAY 1.021277 (-7700 6100);
DISPLAY INVISIBLE (-7700 6100);
FORCEPROP 1 LASTPIN (-7750 6000) $PN 1
J 0
(-7740 5980);
DISPLAY 0.489362 (-7740 5980);
FORCEPROP 1 LASTPIN (-7750 5800) $PN 2
J 0
(-7740 5780);
DISPLAY 0.489362 (-7740 5780);
FORCEPROP 1 LAST MATERIAL X6S
J 0
(-7700 5800);
DISPLAY 0.489362 (-7700 5800);
PAINT SKYBLUE (-7700 5800);
FORCEPROP 1 LAST TOLERANCE 20%
J 0
(-7700 5850);
DISPLAY 0.489362 (-7700 5850);
PAINT SKYBLUE (-7700 5850);
FORCEPROP 1 LAST VALUE 22UF
J 0
(-7700 5950);
DISPLAY 0.489362 (-7700 5950);
PAINT SKYBLUE (-7700 5950);
FORCEPROP 1 LAST PART_NUMBER CH622KMEB02
J 0
(-7700 5750);
DISPLAY 0.489362 (-7700 5750);
PAINT SKYBLUE (-7700 5750);
FORCEPROP 1 LAST VOLTAGE 4V
J 0
(-7700 5900);
DISPLAY 0.489362 (-7700 5900);
PAINT SKYBLUE (-7700 5900);
FORCEPROP 1 LAST PACK_TYPE C0402
J 0
(-7700 5700);
DISPLAY 0.489362 (-7700 5700);
PAINT SKYBLUE (-7700 5700);
FORCEPROP 2 LAST CDS_LIB pure_quanta
J 0
(-7750 5900);
PAINT MONO (-7750 5900);
DISPLAY INVISIBLE (-7750 5900);
FORCEPROP 1 LAST PATH I85
J 0
(-7700 6050);
DISPLAY 0.978723 (-7700 6050);
PAINT WHITE (-7700 6050);
DISPLAY INVISIBLE (-7700 6050);
FORCEADD Q_CAP..1
(-7300 5900);
FORCEPROP 1 LAST LOCATION C2555
J 0
(-7250 6000);
DISPLAY 0.489362 (-7250 6000);
PAINT SKYBLUE (-7250 6000);
FORCEPROP 2 LAST $SEC 1
J 0
(-7250 6100);
DISPLAY 0.680851 (-7250 6100);
PAINT MONO (-7250 6100);
DISPLAY INVISIBLE (-7250 6100);
FORCEPROP 2 LAST CDS_SEC 1
J 0
(-7250 6100);
DISPLAY 1.021277 (-7250 6100);
DISPLAY INVISIBLE (-7250 6100);
FORCEPROP 1 LASTPIN (-7300 6000) $PN 1
J 0
(-7290 5980);
DISPLAY 0.489362 (-7290 5980);
FORCEPROP 1 LASTPIN (-7300 5800) $PN 2
J 0
(-7290 5780);
DISPLAY 0.489362 (-7290 5780);
FORCEPROP 1 LAST MATERIAL X6S
J 0
(-7250 5800);
DISPLAY 0.489362 (-7250 5800);
PAINT SKYBLUE (-7250 5800);
FORCEPROP 1 LAST TOLERANCE 20%
J 0
(-7250 5850);
DISPLAY 0.489362 (-7250 5850);
PAINT SKYBLUE (-7250 5850);
FORCEPROP 1 LAST VALUE 22UF
J 0
(-7250 5950);
DISPLAY 0.489362 (-7250 5950);
PAINT SKYBLUE (-7250 5950);
FORCEPROP 1 LAST PART_NUMBER CH622KMEB02
J 0
(-7250 5750);
DISPLAY 0.489362 (-7250 5750);
PAINT SKYBLUE (-7250 5750);
FORCEPROP 1 LAST VOLTAGE 4V
J 0
(-7250 5900);
DISPLAY 0.489362 (-7250 5900);
PAINT SKYBLUE (-7250 5900);
FORCEPROP 1 LAST PACK_TYPE C0402
J 0
(-7250 5700);
DISPLAY 0.489362 (-7250 5700);
PAINT SKYBLUE (-7250 5700);
FORCEPROP 2 LAST CDS_LIB pure_quanta
J 0
(-7300 5900);
PAINT MONO (-7300 5900);
DISPLAY INVISIBLE (-7300 5900);
FORCEPROP 1 LAST PATH I86
J 0
(-7250 6050);
DISPLAY 0.978723 (-7250 6050);
PAINT WHITE (-7250 6050);
DISPLAY INVISIBLE (-7250 6050);
FORCEADD Q_CAP..1
(-6850 4425);
FORCEPROP 1 LAST LOCATION C2564
J 0
(-6800 4525);
DISPLAY 0.489362 (-6800 4525);
PAINT SKYBLUE (-6800 4525);
FORCEPROP 2 LAST $SEC 1
J 0
(-6800 4625);
DISPLAY 0.680851 (-6800 4625);
PAINT MONO (-6800 4625);
DISPLAY INVISIBLE (-6800 4625);
FORCEPROP 2 LAST CDS_SEC 1
J 0
(-6800 4625);
DISPLAY 1.021277 (-6800 4625);
DISPLAY INVISIBLE (-6800 4625);
FORCEPROP 1 LASTPIN (-6850 4525) $PN 1
J 0
(-6840 4505);
DISPLAY 0.489362 (-6840 4505);
FORCEPROP 1 LASTPIN (-6850 4325) $PN 2
J 0
(-6840 4305);
DISPLAY 0.489362 (-6840 4305);
FORCEPROP 1 LAST MATERIAL X6S
J 0
(-6800 4325);
DISPLAY 0.489362 (-6800 4325);
PAINT SKYBLUE (-6800 4325);
FORCEPROP 1 LAST TOLERANCE 20%
J 0
(-6800 4375);
DISPLAY 0.489362 (-6800 4375);
PAINT SKYBLUE (-6800 4375);
FORCEPROP 1 LAST VALUE 22UF
J 0
(-6800 4475);
DISPLAY 0.489362 (-6800 4475);
PAINT SKYBLUE (-6800 4475);
FORCEPROP 1 LAST PART_NUMBER CH622KMEB02
J 0
(-6800 4275);
DISPLAY 0.489362 (-6800 4275);
PAINT SKYBLUE (-6800 4275);
FORCEPROP 1 LAST VOLTAGE 4V
J 0
(-6800 4425);
DISPLAY 0.489362 (-6800 4425);
PAINT SKYBLUE (-6800 4425);
FORCEPROP 1 LAST PACK_TYPE C0402
J 0
(-6800 4225);
DISPLAY 0.489362 (-6800 4225);
PAINT SKYBLUE (-6800 4225);
FORCEPROP 2 LAST CDS_LIB pure_quanta
J 0
(-6850 4425);
PAINT MONO (-6850 4425);
DISPLAY INVISIBLE (-6850 4425);
FORCEPROP 1 LAST PATH I87
J 0
(-6800 4575);
DISPLAY 0.978723 (-6800 4575);
PAINT WHITE (-6800 4575);
DISPLAY INVISIBLE (-6800 4575);
FORCEADD Q_CAP..1
(-6850 5150);
FORCEPROP 1 LAST LOCATION C2563
J 0
(-6800 5250);
DISPLAY 0.489362 (-6800 5250);
PAINT SKYBLUE (-6800 5250);
FORCEPROP 2 LAST $SEC 1
J 0
(-6800 5350);
DISPLAY 0.680851 (-6800 5350);
PAINT MONO (-6800 5350);
DISPLAY INVISIBLE (-6800 5350);
FORCEPROP 2 LAST CDS_SEC 1
J 0
(-6800 5350);
DISPLAY 1.021277 (-6800 5350);
DISPLAY INVISIBLE (-6800 5350);
FORCEPROP 1 LASTPIN (-6850 5250) $PN 1
J 0
(-6840 5230);
DISPLAY 0.489362 (-6840 5230);
FORCEPROP 1 LASTPIN (-6850 5050) $PN 2
J 0
(-6840 5030);
DISPLAY 0.489362 (-6840 5030);
FORCEPROP 1 LAST MATERIAL X6S
J 0
(-6800 5050);
DISPLAY 0.489362 (-6800 5050);
PAINT SKYBLUE (-6800 5050);
FORCEPROP 1 LAST TOLERANCE 20%
J 0
(-6800 5100);
DISPLAY 0.489362 (-6800 5100);
PAINT SKYBLUE (-6800 5100);
FORCEPROP 1 LAST VALUE 22UF
J 0
(-6800 5200);
DISPLAY 0.489362 (-6800 5200);
PAINT SKYBLUE (-6800 5200);
FORCEPROP 1 LAST PART_NUMBER CH622KMEB02
J 0
(-6800 5000);
DISPLAY 0.489362 (-6800 5000);
PAINT SKYBLUE (-6800 5000);
FORCEPROP 1 LAST VOLTAGE 4V
J 0
(-6800 5150);
DISPLAY 0.489362 (-6800 5150);
PAINT SKYBLUE (-6800 5150);
FORCEPROP 1 LAST PACK_TYPE C0402
J 0
(-6800 4950);
DISPLAY 0.489362 (-6800 4950);
PAINT SKYBLUE (-6800 4950);
FORCEPROP 2 LAST CDS_LIB pure_quanta
J 0
(-6850 5150);
PAINT MONO (-6850 5150);
DISPLAY INVISIBLE (-6850 5150);
FORCEPROP 1 LAST PATH I88
J 0
(-6800 5300);
DISPLAY 0.978723 (-6800 5300);
PAINT WHITE (-6800 5300);
DISPLAY INVISIBLE (-6800 5300);
FORCEADD Q_CAP..1
(-6400 4425);
FORCEPROP 1 LAST LOCATION C2571
J 0
(-6350 4525);
DISPLAY 0.489362 (-6350 4525);
PAINT SKYBLUE (-6350 4525);
FORCEPROP 2 LAST $SEC 1
J 0
(-6350 4625);
DISPLAY 0.680851 (-6350 4625);
PAINT MONO (-6350 4625);
DISPLAY INVISIBLE (-6350 4625);
FORCEPROP 2 LAST CDS_SEC 1
J 0
(-6350 4625);
DISPLAY 1.021277 (-6350 4625);
DISPLAY INVISIBLE (-6350 4625);
FORCEPROP 1 LASTPIN (-6400 4525) $PN 1
J 0
(-6390 4505);
DISPLAY 0.489362 (-6390 4505);
FORCEPROP 1 LASTPIN (-6400 4325) $PN 2
J 0
(-6390 4305);
DISPLAY 0.489362 (-6390 4305);
FORCEPROP 1 LAST MATERIAL X6S
J 0
(-6350 4325);
DISPLAY 0.489362 (-6350 4325);
PAINT SKYBLUE (-6350 4325);
FORCEPROP 1 LAST TOLERANCE 20%
J 0
(-6350 4375);
DISPLAY 0.489362 (-6350 4375);
PAINT SKYBLUE (-6350 4375);
FORCEPROP 1 LAST VALUE 22UF
J 0
(-6350 4475);
DISPLAY 0.489362 (-6350 4475);
PAINT SKYBLUE (-6350 4475);
FORCEPROP 1 LAST PART_NUMBER CH622KMEB02
J 0
(-6350 4275);
DISPLAY 0.489362 (-6350 4275);
PAINT SKYBLUE (-6350 4275);
FORCEPROP 1 LAST VOLTAGE 4V
J 0
(-6350 4425);
DISPLAY 0.489362 (-6350 4425);
PAINT SKYBLUE (-6350 4425);
FORCEPROP 1 LAST PACK_TYPE C0402
J 0
(-6350 4225);
DISPLAY 0.489362 (-6350 4225);
PAINT SKYBLUE (-6350 4225);
FORCEPROP 2 LAST CDS_LIB pure_quanta
J 0
(-6400 4425);
PAINT MONO (-6400 4425);
DISPLAY INVISIBLE (-6400 4425);
FORCEPROP 1 LAST PATH I89
J 0
(-6350 4575);
DISPLAY 0.978723 (-6350 4575);
PAINT WHITE (-6350 4575);
DISPLAY INVISIBLE (-6350 4575);
FORCEADD Q_CAP..1
(-9075 3000);
FORCEPROP 1 LAST LOCATION C2531
J 0
(-9025 3100);
DISPLAY 0.489362 (-9025 3100);
PAINT SKYBLUE (-9025 3100);
FORCEPROP 2 LAST $SEC 1
J 0
(-9025 3200);
DISPLAY 0.680851 (-9025 3200);
PAINT MONO (-9025 3200);
DISPLAY INVISIBLE (-9025 3200);
FORCEPROP 2 LAST CDS_SEC 1
J 0
(-9025 3200);
DISPLAY 1.021277 (-9025 3200);
DISPLAY INVISIBLE (-9025 3200);
FORCEPROP 1 LASTPIN (-9075 3100) $PN 1
J 0
(-9065 3080);
DISPLAY 0.489362 (-9065 3080);
FORCEPROP 1 LASTPIN (-9075 2900) $PN 2
J 0
(-9065 2880);
DISPLAY 0.489362 (-9065 2880);
FORCEPROP 1 LAST MATERIAL X6S
J 0
(-9025 2900);
DISPLAY 0.489362 (-9025 2900);
PAINT SKYBLUE (-9025 2900);
FORCEPROP 1 LAST TOLERANCE 20%
J 0
(-9025 2950);
DISPLAY 0.489362 (-9025 2950);
PAINT SKYBLUE (-9025 2950);
FORCEPROP 1 LAST VALUE 22UF
J 0
(-9025 3050);
DISPLAY 0.489362 (-9025 3050);
PAINT SKYBLUE (-9025 3050);
FORCEPROP 1 LAST PART_NUMBER CH622KMEB02
J 0
(-9025 2850);
DISPLAY 0.489362 (-9025 2850);
PAINT SKYBLUE (-9025 2850);
FORCEPROP 1 LAST VOLTAGE 4V
J 0
(-9025 3000);
DISPLAY 0.489362 (-9025 3000);
PAINT SKYBLUE (-9025 3000);
FORCEPROP 1 LAST PACK_TYPE C0402
J 0
(-9025 2800);
DISPLAY 0.489362 (-9025 2800);
PAINT SKYBLUE (-9025 2800);
FORCEPROP 2 LAST CDS_LIB pure_quanta
J 0
(-9075 3000);
PAINT MONO (-9075 3000);
DISPLAY INVISIBLE (-9075 3000);
FORCEPROP 1 LAST PATH I9
J 0
(-9025 3150);
DISPLAY 0.978723 (-9025 3150);
PAINT WHITE (-9025 3150);
DISPLAY INVISIBLE (-9025 3150);
FORCEADD Q_CAP..1
(-6400 5150);
FORCEPROP 1 LAST LOCATION C2570
J 0
(-6350 5250);
DISPLAY 0.489362 (-6350 5250);
PAINT SKYBLUE (-6350 5250);
FORCEPROP 2 LAST $SEC 1
J 0
(-6350 5350);
DISPLAY 0.680851 (-6350 5350);
PAINT MONO (-6350 5350);
DISPLAY INVISIBLE (-6350 5350);
FORCEPROP 2 LAST CDS_SEC 1
J 0
(-6350 5350);
DISPLAY 1.021277 (-6350 5350);
DISPLAY INVISIBLE (-6350 5350);
FORCEPROP 1 LASTPIN (-6400 5250) $PN 1
J 0
(-6390 5230);
DISPLAY 0.489362 (-6390 5230);
FORCEPROP 1 LASTPIN (-6400 5050) $PN 2
J 0
(-6390 5030);
DISPLAY 0.489362 (-6390 5030);
FORCEPROP 1 LAST MATERIAL X6S
J 0
(-6350 5050);
DISPLAY 0.489362 (-6350 5050);
PAINT SKYBLUE (-6350 5050);
FORCEPROP 1 LAST TOLERANCE 20%
J 0
(-6350 5100);
DISPLAY 0.489362 (-6350 5100);
PAINT SKYBLUE (-6350 5100);
FORCEPROP 1 LAST VALUE 22UF
J 0
(-6350 5200);
DISPLAY 0.489362 (-6350 5200);
PAINT SKYBLUE (-6350 5200);
FORCEPROP 1 LAST PART_NUMBER CH622KMEB02
J 0
(-6350 5000);
DISPLAY 0.489362 (-6350 5000);
PAINT SKYBLUE (-6350 5000);
FORCEPROP 1 LAST VOLTAGE 4V
J 0
(-6350 5150);
DISPLAY 0.489362 (-6350 5150);
PAINT SKYBLUE (-6350 5150);
FORCEPROP 1 LAST PACK_TYPE C0402
J 0
(-6350 4950);
DISPLAY 0.489362 (-6350 4950);
PAINT SKYBLUE (-6350 4950);
FORCEPROP 2 LAST CDS_LIB pure_quanta
J 0
(-6400 5150);
PAINT MONO (-6400 5150);
DISPLAY INVISIBLE (-6400 5150);
FORCEPROP 1 LAST PATH I90
J 0
(-6350 5300);
DISPLAY 0.978723 (-6350 5300);
PAINT WHITE (-6350 5300);
DISPLAY INVISIBLE (-6350 5300);
FORCEADD Q_CAP..1
(-6850 5900);
FORCEPROP 1 LAST LOCATION C2562
J 0
(-6800 6000);
DISPLAY 0.489362 (-6800 6000);
PAINT SKYBLUE (-6800 6000);
FORCEPROP 2 LAST $SEC 1
J 0
(-6800 6100);
DISPLAY 0.680851 (-6800 6100);
PAINT MONO (-6800 6100);
DISPLAY INVISIBLE (-6800 6100);
FORCEPROP 2 LAST CDS_SEC 1
J 0
(-6800 6100);
DISPLAY 1.021277 (-6800 6100);
DISPLAY INVISIBLE (-6800 6100);
FORCEPROP 1 LASTPIN (-6850 6000) $PN 1
J 0
(-6840 5980);
DISPLAY 0.489362 (-6840 5980);
FORCEPROP 1 LASTPIN (-6850 5800) $PN 2
J 0
(-6840 5780);
DISPLAY 0.489362 (-6840 5780);
FORCEPROP 1 LAST MATERIAL X6S
J 0
(-6800 5800);
DISPLAY 0.489362 (-6800 5800);
PAINT SKYBLUE (-6800 5800);
FORCEPROP 1 LAST TOLERANCE 20%
J 0
(-6800 5850);
DISPLAY 0.489362 (-6800 5850);
PAINT SKYBLUE (-6800 5850);
FORCEPROP 1 LAST VALUE 22UF
J 0
(-6800 5950);
DISPLAY 0.489362 (-6800 5950);
PAINT SKYBLUE (-6800 5950);
FORCEPROP 1 LAST PART_NUMBER CH622KMEB02
J 0
(-6800 5750);
DISPLAY 0.489362 (-6800 5750);
PAINT SKYBLUE (-6800 5750);
FORCEPROP 1 LAST VOLTAGE 4V
J 0
(-6800 5900);
DISPLAY 0.489362 (-6800 5900);
PAINT SKYBLUE (-6800 5900);
FORCEPROP 1 LAST PACK_TYPE C0402
J 0
(-6800 5700);
DISPLAY 0.489362 (-6800 5700);
PAINT SKYBLUE (-6800 5700);
FORCEPROP 2 LAST CDS_LIB pure_quanta
J 0
(-6850 5900);
PAINT MONO (-6850 5900);
DISPLAY INVISIBLE (-6850 5900);
FORCEPROP 1 LAST PATH I91
J 0
(-6800 6050);
DISPLAY 0.978723 (-6800 6050);
PAINT WHITE (-6800 6050);
DISPLAY INVISIBLE (-6800 6050);
FORCEADD Q_CAP..1
(-6400 5900);
FORCEPROP 1 LAST LOCATION C2569
J 0
(-6350 6000);
DISPLAY 0.489362 (-6350 6000);
PAINT SKYBLUE (-6350 6000);
FORCEPROP 2 LAST $SEC 1
J 0
(-6350 6100);
DISPLAY 0.680851 (-6350 6100);
PAINT MONO (-6350 6100);
DISPLAY INVISIBLE (-6350 6100);
FORCEPROP 2 LAST CDS_SEC 1
J 0
(-6350 6100);
DISPLAY 1.021277 (-6350 6100);
DISPLAY INVISIBLE (-6350 6100);
FORCEPROP 1 LASTPIN (-6400 6000) $PN 1
J 0
(-6390 5980);
DISPLAY 0.489362 (-6390 5980);
FORCEPROP 1 LASTPIN (-6400 5800) $PN 2
J 0
(-6390 5780);
DISPLAY 0.489362 (-6390 5780);
FORCEPROP 1 LAST MATERIAL X6S
J 0
(-6350 5800);
DISPLAY 0.489362 (-6350 5800);
PAINT SKYBLUE (-6350 5800);
FORCEPROP 1 LAST TOLERANCE 20%
J 0
(-6350 5850);
DISPLAY 0.489362 (-6350 5850);
PAINT SKYBLUE (-6350 5850);
FORCEPROP 1 LAST VALUE 22UF
J 0
(-6350 5950);
DISPLAY 0.489362 (-6350 5950);
PAINT SKYBLUE (-6350 5950);
FORCEPROP 1 LAST PART_NUMBER CH622KMEB02
J 0
(-6350 5750);
DISPLAY 0.489362 (-6350 5750);
PAINT SKYBLUE (-6350 5750);
FORCEPROP 1 LAST VOLTAGE 4V
J 0
(-6350 5900);
DISPLAY 0.489362 (-6350 5900);
PAINT SKYBLUE (-6350 5900);
FORCEPROP 1 LAST PACK_TYPE C0402
J 0
(-6350 5700);
DISPLAY 0.489362 (-6350 5700);
PAINT SKYBLUE (-6350 5700);
FORCEPROP 2 LAST CDS_LIB pure_quanta
J 0
(-6400 5900);
PAINT MONO (-6400 5900);
DISPLAY INVISIBLE (-6400 5900);
FORCEPROP 1 LAST PATH I92
J 0
(-6350 6050);
DISPLAY 0.978723 (-6350 6050);
PAINT WHITE (-6350 6050);
DISPLAY INVISIBLE (-6350 6050);
FORCEADD Q_CAP..1
(-5950 4425);
FORCEPROP 1 LAST LOCATION C2578
J 0
(-5900 4525);
DISPLAY 0.489362 (-5900 4525);
PAINT SKYBLUE (-5900 4525);
FORCEPROP 2 LAST $SEC 1
J 0
(-5900 4625);
DISPLAY 0.680851 (-5900 4625);
PAINT MONO (-5900 4625);
DISPLAY INVISIBLE (-5900 4625);
FORCEPROP 2 LAST CDS_SEC 1
J 0
(-5900 4625);
DISPLAY 1.021277 (-5900 4625);
DISPLAY INVISIBLE (-5900 4625);
FORCEPROP 1 LASTPIN (-5950 4525) $PN 1
J 0
(-5940 4505);
DISPLAY 0.489362 (-5940 4505);
FORCEPROP 1 LASTPIN (-5950 4325) $PN 2
J 0
(-5940 4305);
DISPLAY 0.489362 (-5940 4305);
FORCEPROP 1 LAST MATERIAL X6S
J 0
(-5900 4325);
DISPLAY 0.489362 (-5900 4325);
PAINT SKYBLUE (-5900 4325);
FORCEPROP 1 LAST TOLERANCE 20%
J 0
(-5900 4375);
DISPLAY 0.489362 (-5900 4375);
PAINT SKYBLUE (-5900 4375);
FORCEPROP 1 LAST VALUE 22UF
J 0
(-5900 4475);
DISPLAY 0.489362 (-5900 4475);
PAINT SKYBLUE (-5900 4475);
FORCEPROP 1 LAST PART_NUMBER CH622KMEB02
J 0
(-5900 4275);
DISPLAY 0.489362 (-5900 4275);
PAINT SKYBLUE (-5900 4275);
FORCEPROP 1 LAST VOLTAGE 4V
J 0
(-5900 4425);
DISPLAY 0.489362 (-5900 4425);
PAINT SKYBLUE (-5900 4425);
FORCEPROP 1 LAST PACK_TYPE C0402
J 0
(-5900 4225);
DISPLAY 0.489362 (-5900 4225);
PAINT SKYBLUE (-5900 4225);
FORCEPROP 2 LAST CDS_LIB pure_quanta
J 0
(-5950 4425);
PAINT MONO (-5950 4425);
DISPLAY INVISIBLE (-5950 4425);
FORCEPROP 1 LAST PATH I93
J 0
(-5900 4575);
DISPLAY 0.978723 (-5900 4575);
PAINT WHITE (-5900 4575);
DISPLAY INVISIBLE (-5900 4575);
FORCEADD Q_CAP..1
(-5950 5150);
FORCEPROP 1 LAST LOCATION C2577
J 0
(-5900 5250);
DISPLAY 0.489362 (-5900 5250);
PAINT SKYBLUE (-5900 5250);
FORCEPROP 2 LAST $SEC 1
J 0
(-5900 5350);
DISPLAY 0.680851 (-5900 5350);
PAINT MONO (-5900 5350);
DISPLAY INVISIBLE (-5900 5350);
FORCEPROP 2 LAST CDS_SEC 1
J 0
(-5900 5350);
DISPLAY 1.021277 (-5900 5350);
DISPLAY INVISIBLE (-5900 5350);
FORCEPROP 1 LASTPIN (-5950 5250) $PN 1
J 0
(-5940 5230);
DISPLAY 0.489362 (-5940 5230);
FORCEPROP 1 LASTPIN (-5950 5050) $PN 2
J 0
(-5940 5030);
DISPLAY 0.489362 (-5940 5030);
FORCEPROP 1 LAST MATERIAL X6S
J 0
(-5900 5050);
DISPLAY 0.489362 (-5900 5050);
PAINT SKYBLUE (-5900 5050);
FORCEPROP 1 LAST TOLERANCE 20%
J 0
(-5900 5100);
DISPLAY 0.489362 (-5900 5100);
PAINT SKYBLUE (-5900 5100);
FORCEPROP 1 LAST VALUE 22UF
J 0
(-5900 5200);
DISPLAY 0.489362 (-5900 5200);
PAINT SKYBLUE (-5900 5200);
FORCEPROP 1 LAST PART_NUMBER CH622KMEB02
J 0
(-5900 5000);
DISPLAY 0.489362 (-5900 5000);
PAINT SKYBLUE (-5900 5000);
FORCEPROP 1 LAST VOLTAGE 4V
J 0
(-5900 5150);
DISPLAY 0.489362 (-5900 5150);
PAINT SKYBLUE (-5900 5150);
FORCEPROP 1 LAST PACK_TYPE C0402
J 0
(-5900 4950);
DISPLAY 0.489362 (-5900 4950);
PAINT SKYBLUE (-5900 4950);
FORCEPROP 2 LAST CDS_LIB pure_quanta
J 0
(-5950 5150);
PAINT MONO (-5950 5150);
DISPLAY INVISIBLE (-5950 5150);
FORCEPROP 1 LAST PATH I94
J 0
(-5900 5300);
DISPLAY 0.978723 (-5900 5300);
PAINT WHITE (-5900 5300);
DISPLAY INVISIBLE (-5900 5300);
FORCEADD Q_CAP..1
(-5500 4425);
FORCEPROP 1 LAST LOCATION C2585
J 0
(-5450 4525);
DISPLAY 0.489362 (-5450 4525);
PAINT SKYBLUE (-5450 4525);
FORCEPROP 2 LAST $SEC 1
J 0
(-5450 4625);
DISPLAY 0.680851 (-5450 4625);
PAINT MONO (-5450 4625);
DISPLAY INVISIBLE (-5450 4625);
FORCEPROP 2 LAST CDS_SEC 1
J 0
(-5450 4625);
DISPLAY 1.021277 (-5450 4625);
DISPLAY INVISIBLE (-5450 4625);
FORCEPROP 1 LASTPIN (-5500 4525) $PN 1
J 0
(-5490 4505);
DISPLAY 0.489362 (-5490 4505);
FORCEPROP 1 LASTPIN (-5500 4325) $PN 2
J 0
(-5490 4305);
DISPLAY 0.489362 (-5490 4305);
FORCEPROP 1 LAST MATERIAL X6S
J 0
(-5450 4325);
DISPLAY 0.489362 (-5450 4325);
PAINT SKYBLUE (-5450 4325);
FORCEPROP 1 LAST TOLERANCE 20%
J 0
(-5450 4375);
DISPLAY 0.489362 (-5450 4375);
PAINT SKYBLUE (-5450 4375);
FORCEPROP 1 LAST VALUE 22UF
J 0
(-5450 4475);
DISPLAY 0.489362 (-5450 4475);
PAINT SKYBLUE (-5450 4475);
FORCEPROP 1 LAST PART_NUMBER CH622KMEB02
J 0
(-5450 4275);
DISPLAY 0.489362 (-5450 4275);
PAINT SKYBLUE (-5450 4275);
FORCEPROP 1 LAST VOLTAGE 4V
J 0
(-5450 4425);
DISPLAY 0.489362 (-5450 4425);
PAINT SKYBLUE (-5450 4425);
FORCEPROP 1 LAST PACK_TYPE C0402
J 0
(-5450 4225);
DISPLAY 0.489362 (-5450 4225);
PAINT SKYBLUE (-5450 4225);
FORCEPROP 2 LAST CDS_LIB pure_quanta
J 0
(-5500 4425);
PAINT MONO (-5500 4425);
DISPLAY INVISIBLE (-5500 4425);
FORCEPROP 1 LAST PATH I95
J 0
(-5450 4575);
DISPLAY 0.978723 (-5450 4575);
PAINT WHITE (-5450 4575);
DISPLAY INVISIBLE (-5450 4575);
FORCEADD Q_CAP..1
(-5500 5150);
FORCEPROP 1 LAST LOCATION C2584
J 0
(-5450 5250);
DISPLAY 0.489362 (-5450 5250);
PAINT SKYBLUE (-5450 5250);
FORCEPROP 2 LAST $SEC 1
J 0
(-5450 5350);
DISPLAY 0.680851 (-5450 5350);
PAINT MONO (-5450 5350);
DISPLAY INVISIBLE (-5450 5350);
FORCEPROP 2 LAST CDS_SEC 1
J 0
(-5450 5350);
DISPLAY 1.021277 (-5450 5350);
DISPLAY INVISIBLE (-5450 5350);
FORCEPROP 1 LASTPIN (-5500 5250) $PN 1
J 0
(-5490 5230);
DISPLAY 0.489362 (-5490 5230);
FORCEPROP 1 LASTPIN (-5500 5050) $PN 2
J 0
(-5490 5030);
DISPLAY 0.489362 (-5490 5030);
FORCEPROP 1 LAST MATERIAL X6S
J 0
(-5450 5050);
DISPLAY 0.489362 (-5450 5050);
PAINT SKYBLUE (-5450 5050);
FORCEPROP 1 LAST TOLERANCE 20%
J 0
(-5450 5100);
DISPLAY 0.489362 (-5450 5100);
PAINT SKYBLUE (-5450 5100);
FORCEPROP 1 LAST VALUE 22UF
J 0
(-5450 5200);
DISPLAY 0.489362 (-5450 5200);
PAINT SKYBLUE (-5450 5200);
FORCEPROP 1 LAST PART_NUMBER CH622KMEB02
J 0
(-5450 5000);
DISPLAY 0.489362 (-5450 5000);
PAINT SKYBLUE (-5450 5000);
FORCEPROP 1 LAST VOLTAGE 4V
J 0
(-5450 5150);
DISPLAY 0.489362 (-5450 5150);
PAINT SKYBLUE (-5450 5150);
FORCEPROP 1 LAST PACK_TYPE C0402
J 0
(-5450 4950);
DISPLAY 0.489362 (-5450 4950);
PAINT SKYBLUE (-5450 4950);
FORCEPROP 2 LAST CDS_LIB pure_quanta
J 0
(-5500 5150);
PAINT MONO (-5500 5150);
DISPLAY INVISIBLE (-5500 5150);
FORCEPROP 1 LAST PATH I96
J 0
(-5450 5300);
DISPLAY 0.978723 (-5450 5300);
PAINT WHITE (-5450 5300);
DISPLAY INVISIBLE (-5450 5300);
FORCEADD Q_CAP..1
(-5950 5900);
FORCEPROP 1 LAST LOCATION C2576
J 0
(-5900 6000);
DISPLAY 0.489362 (-5900 6000);
PAINT SKYBLUE (-5900 6000);
FORCEPROP 2 LAST $SEC 1
J 0
(-5900 6100);
DISPLAY 0.680851 (-5900 6100);
PAINT MONO (-5900 6100);
DISPLAY INVISIBLE (-5900 6100);
FORCEPROP 2 LAST CDS_SEC 1
J 0
(-5900 6100);
DISPLAY 1.021277 (-5900 6100);
DISPLAY INVISIBLE (-5900 6100);
FORCEPROP 1 LASTPIN (-5950 6000) $PN 1
J 0
(-5940 5980);
DISPLAY 0.489362 (-5940 5980);
FORCEPROP 1 LASTPIN (-5950 5800) $PN 2
J 0
(-5940 5780);
DISPLAY 0.489362 (-5940 5780);
FORCEPROP 1 LAST MATERIAL X6S
J 0
(-5900 5800);
DISPLAY 0.489362 (-5900 5800);
PAINT SKYBLUE (-5900 5800);
FORCEPROP 1 LAST TOLERANCE 20%
J 0
(-5900 5850);
DISPLAY 0.489362 (-5900 5850);
PAINT SKYBLUE (-5900 5850);
FORCEPROP 1 LAST VALUE 22UF
J 0
(-5900 5950);
DISPLAY 0.489362 (-5900 5950);
PAINT SKYBLUE (-5900 5950);
FORCEPROP 1 LAST PART_NUMBER CH622KMEB02
J 0
(-5900 5750);
DISPLAY 0.489362 (-5900 5750);
PAINT SKYBLUE (-5900 5750);
FORCEPROP 1 LAST VOLTAGE 4V
J 0
(-5900 5900);
DISPLAY 0.489362 (-5900 5900);
PAINT SKYBLUE (-5900 5900);
FORCEPROP 1 LAST PACK_TYPE C0402
J 0
(-5900 5700);
DISPLAY 0.489362 (-5900 5700);
PAINT SKYBLUE (-5900 5700);
FORCEPROP 2 LAST CDS_LIB pure_quanta
J 0
(-5950 5900);
PAINT MONO (-5950 5900);
DISPLAY INVISIBLE (-5950 5900);
FORCEPROP 1 LAST PATH I97
J 0
(-5900 6050);
DISPLAY 0.978723 (-5900 6050);
PAINT WHITE (-5900 6050);
DISPLAY INVISIBLE (-5900 6050);
FORCEADD Q_CAP..1
(-5500 5900);
FORCEPROP 1 LAST LOCATION C2583
J 0
(-5450 6000);
DISPLAY 0.489362 (-5450 6000);
PAINT SKYBLUE (-5450 6000);
FORCEPROP 2 LAST $SEC 1
J 0
(-5450 6100);
DISPLAY 0.680851 (-5450 6100);
PAINT MONO (-5450 6100);
DISPLAY INVISIBLE (-5450 6100);
FORCEPROP 2 LAST CDS_SEC 1
J 0
(-5450 6100);
DISPLAY 1.021277 (-5450 6100);
DISPLAY INVISIBLE (-5450 6100);
FORCEPROP 1 LASTPIN (-5500 6000) $PN 1
J 0
(-5490 5980);
DISPLAY 0.489362 (-5490 5980);
FORCEPROP 1 LASTPIN (-5500 5800) $PN 2
J 0
(-5490 5780);
DISPLAY 0.489362 (-5490 5780);
FORCEPROP 1 LAST MATERIAL X6S
J 0
(-5450 5800);
DISPLAY 0.489362 (-5450 5800);
PAINT SKYBLUE (-5450 5800);
FORCEPROP 1 LAST TOLERANCE 20%
J 0
(-5450 5850);
DISPLAY 0.489362 (-5450 5850);
PAINT SKYBLUE (-5450 5850);
FORCEPROP 1 LAST VALUE 22UF
J 0
(-5450 5950);
DISPLAY 0.489362 (-5450 5950);
PAINT SKYBLUE (-5450 5950);
FORCEPROP 1 LAST PART_NUMBER CH622KMEB02
J 0
(-5450 5750);
DISPLAY 0.489362 (-5450 5750);
PAINT SKYBLUE (-5450 5750);
FORCEPROP 1 LAST VOLTAGE 4V
J 0
(-5450 5900);
DISPLAY 0.489362 (-5450 5900);
PAINT SKYBLUE (-5450 5900);
FORCEPROP 1 LAST PACK_TYPE C0402
J 0
(-5450 5700);
DISPLAY 0.489362 (-5450 5700);
PAINT SKYBLUE (-5450 5700);
FORCEPROP 2 LAST CDS_LIB pure_quanta
J 0
(-5500 5900);
PAINT MONO (-5500 5900);
DISPLAY INVISIBLE (-5500 5900);
FORCEPROP 1 LAST PATH I98
J 0
(-5450 6050);
DISPLAY 0.978723 (-5450 6050);
PAINT WHITE (-5450 6050);
DISPLAY INVISIBLE (-5450 6050);
FORCEADD Q_CAP..1
(-5100 4425);
FORCEPROP 1 LAST LOCATION C2592
J 0
(-5050 4525);
DISPLAY 0.489362 (-5050 4525);
PAINT SKYBLUE (-5050 4525);
FORCEPROP 2 LAST $SEC 1
J 0
(-5050 4625);
DISPLAY 0.680851 (-5050 4625);
PAINT MONO (-5050 4625);
DISPLAY INVISIBLE (-5050 4625);
FORCEPROP 2 LAST CDS_SEC 1
J 0
(-5050 4625);
DISPLAY 1.021277 (-5050 4625);
DISPLAY INVISIBLE (-5050 4625);
FORCEPROP 1 LASTPIN (-5100 4525) $PN 1
J 0
(-5090 4505);
DISPLAY 0.489362 (-5090 4505);
FORCEPROP 1 LASTPIN (-5100 4325) $PN 2
J 0
(-5090 4305);
DISPLAY 0.489362 (-5090 4305);
FORCEPROP 1 LAST MATERIAL X6S
J 0
(-5050 4325);
DISPLAY 0.489362 (-5050 4325);
PAINT SKYBLUE (-5050 4325);
FORCEPROP 1 LAST TOLERANCE 20%
J 0
(-5050 4375);
DISPLAY 0.489362 (-5050 4375);
PAINT SKYBLUE (-5050 4375);
FORCEPROP 1 LAST VALUE 22UF
J 0
(-5050 4475);
DISPLAY 0.489362 (-5050 4475);
PAINT SKYBLUE (-5050 4475);
FORCEPROP 1 LAST PART_NUMBER CH622KMEB02
J 0
(-5050 4275);
DISPLAY 0.489362 (-5050 4275);
PAINT SKYBLUE (-5050 4275);
FORCEPROP 1 LAST VOLTAGE 4V
J 0
(-5050 4425);
DISPLAY 0.489362 (-5050 4425);
PAINT SKYBLUE (-5050 4425);
FORCEPROP 1 LAST PACK_TYPE C0402
J 0
(-5050 4225);
DISPLAY 0.489362 (-5050 4225);
PAINT SKYBLUE (-5050 4225);
FORCEPROP 2 LAST CDS_LIB pure_quanta
J 0
(-5100 4425);
PAINT MONO (-5100 4425);
DISPLAY INVISIBLE (-5100 4425);
FORCEPROP 1 LAST PATH I99
J 0
(-5050 4575);
DISPLAY 0.978723 (-5050 4575);
PAINT WHITE (-5050 4575);
DISPLAY INVISIBLE (-5050 4575);
FORCEADD QUANTA_TITLE_BLOCK_C..1
(0 0);
FORCEPROP 0 LAST CDS_CON_LAST_MODIFIED Fri Mar 11 14:52:45 2022
J 0
(-1885 15);
DISPLAY INVISIBLE (-1885 15);
FORCEPROP 1 LAST CUSTOM_TXT_CDS <CON_LAST_MODIFIED>
J 0
(-1885 15);
DISPLAY 0.978723 (-1885 15);
FORCEPROP 2 LAST CUSTOM_TXT_CDS <XR_PAGE_TITLE>
J 0
(-7890 5250);
DISPLAY 0.638298 (-7890 5250);
PAINT PINK (-7890 5250);
DISPLAY INVISIBLE (-7890 5250);
FORCEPROP 1 LAST CUSTOM_TXT_CDS <NAME_2>
J 0
(-3175 50);
FORCEPROP 1 LAST CUSTOM_TXT_CDS <NAME_1>
J 0
(-3175 175);
FORCEPROP 1 LAST CUSTOM_TXT_CDS <Q_NUMBER>
J 0
(-1403 103);
DISPLAY 1.212766 (-1403 103);
FORCEPROP 1 LAST CUSTOM_TXT_CDS <Q_PROJ>
J 0
(-2382 102);
DISPLAY 1.212766 (-2382 102);
FORCEPROP 1 LAST CUSTOM_TXT_CDS <Q_REV>
J 0
(-184 103);
DISPLAY 1.212766 (-184 103);
FORCEPROP 1 LAST CUSTOM_TXT_CDS <CON_PAGE_NUM> OF <CON_TOTAL_PAGES>
J 0
(-446 18);
DISPLAY 0.978723 (-446 18);
FORCEPROP 1 LAST Q_DEPT BU9
J 1
(-3763 49);
DISPLAY 1.957447 (-3763 49);
PAINT GREEN (-3763 49);
FORCEPROP 1 LAST Q_TITLE CPU0 CAVITY BOT DECOUPLING CAPS 2/3
J 0
(-9275 50);
DISPLAY 2.446809 (-9275 50);
PAINT GREEN (-9275 50);
FORCEPROP 2 LAST PAGE_BORDER TRUE
J 0
(-7890 5250);
DISPLAY 0.638298 (-7890 5250);
PAINT PINK (-7890 5250);
DISPLAY INVISIBLE (-7890 5250);
FORCEPROP 2 LAST CDS_LIB pure_quanta
J 0
(0 0);
DISPLAY INVISIBLE (0 0);
FORCEPROP 1 LAST CDS_LMAN_SYM_OUTLINE -9475,6775,100,-125
J 0
(0 0);
DISPLAY 0.468085 (0 0);
PAINT GREEN (0 0);
DISPLAY INVISIBLE (0 0);
FORCEPROP 1 LAST COMMENT_BODY TRUE
J 0
(12 -13);
DISPLAY 0.978723 (12 -13);
PAINT GREEN (12 -13);
DISPLAY INVISIBLE (12 -13);
FORCEPROP 2 LAST CDS_XR_PAGE_TITLE CR-69 : @T6G_MB_LIB.T6G(SCH_1):PAGE69
J 0
(-7890 5250);
DISPLAY 0.638298 (-7890 5250);
PAINT PINK (-7890 5250);
DISPLAY INVISIBLE (-7890 5250);
WIRE 16 -1 (-8625 650)(-9075 650);
WIRE 16 -1 (-8175 650)(-8625 650);
WIRE 16 -1 (-8625 650)(-8625 775);
WIRE 16 -1 (-9075 650)(-9075 775);
WIRE 16 -1 (-7725 650)(-8175 650);
WIRE 16 -1 (-8175 650)(-8175 775);
WIRE 16 -1 (-7275 650)(-7725 650);
WIRE 16 -1 (-7725 650)(-7725 775);
WIRE 16 -1 (-6825 650)(-7275 650);
WIRE 16 -1 (-7275 650)(-7275 775);
WIRE 16 -1 (-6375 650)(-6825 650);
WIRE 16 -1 (-6825 650)(-6825 775);
WIRE 16 -1 (-6375 550)(-6375 650);
WIRE 16 -1 (-6375 650)(-6375 775);
WIRE 16 -1 (-5075 1675)(-5075 1750);
WIRE 16 -1 (-5075 1750)(-5475 1750);
WIRE 16 -1 (-5475 1750)(-5475 1675);
WIRE 16 -1 (-5475 1750)(-5925 1750);
WIRE 16 -1 (-5925 1675)(-5925 1750);
WIRE 16 -1 (-5925 1750)(-6375 1750);
WIRE 16 -1 (-6375 1675)(-6375 1750);
WIRE 16 -1 (-6375 1750)(-6825 1750);
WIRE 16 -1 (-6825 1750)(-6825 1675);
WIRE 16 -1 (-6825 1750)(-7275 1750);
WIRE 16 -1 (-7275 1675)(-7275 1750);
WIRE 16 -1 (-7275 1750)(-7725 1750);
WIRE 16 -1 (-7725 1675)(-7725 1750);
WIRE 16 -1 (-7725 1750)(-8175 1750);
WIRE 16 -1 (-8175 1750)(-8175 1675);
WIRE 16 -1 (-8175 1750)(-8625 1750);
WIRE 16 -1 (-8625 1750)(-9075 1750);
WIRE 16 -1 (-8625 1675)(-8625 1750);
WIRE 16 -1 (-9075 1750)(-9075 1800);
WIRE 16 -1 (-9075 1750)(-9075 1675);
WIRE 16 -1 (-8625 1350)(-9075 1350);
WIRE 16 -1 (-8175 1350)(-8625 1350);
WIRE 16 -1 (-8625 1350)(-8625 1475);
WIRE 16 -1 (-9075 1350)(-9075 1475);
WIRE 16 -1 (-7725 1350)(-8175 1350);
WIRE 16 -1 (-8175 1350)(-8175 1475);
WIRE 16 -1 (-7275 1350)(-7725 1350);
WIRE 16 -1 (-7725 1350)(-7725 1475);
WIRE 16 -1 (-6825 1350)(-7275 1350);
WIRE 16 -1 (-7275 1350)(-7275 1475);
WIRE 16 -1 (-6375 1350)(-6825 1350);
WIRE 16 -1 (-6825 1350)(-6825 1475);
WIRE 16 -1 (-5925 1350)(-6375 1350);
WIRE 16 -1 (-6375 1350)(-6375 1475);
WIRE 16 -1 (-5475 1350)(-5925 1350);
WIRE 16 -1 (-5925 1350)(-5925 1475);
WIRE 16 -1 (-5075 1350)(-5475 1350);
WIRE 16 -1 (-5475 1350)(-5475 1475);
WIRE 16 -1 (-5075 1350)(-5075 1475);
WIRE 16 -1 (-5075 1250)(-5075 1350);
WIRE 16 -1 (-6375 975)(-6375 1050);
WIRE 16 -1 (-6375 1050)(-6825 1050);
WIRE 16 -1 (-6825 1050)(-6825 975);
WIRE 16 -1 (-6825 1050)(-7275 1050);
WIRE 16 -1 (-7275 975)(-7275 1050);
WIRE 16 -1 (-7275 1050)(-7725 1050);
WIRE 16 -1 (-7725 975)(-7725 1050);
WIRE 16 -1 (-7725 1050)(-8175 1050);
WIRE 16 -1 (-8175 1050)(-8175 975);
WIRE 16 -1 (-8175 1050)(-8625 1050);
WIRE 16 -1 (-8625 1050)(-9075 1050);
WIRE 16 -1 (-8625 975)(-8625 1050);
WIRE 16 -1 (-9075 1050)(-9075 1100);
WIRE 16 -1 (-9075 1050)(-9075 975);
WIRE 16 -1 (-8625 2775)(-9075 2775);
WIRE 16 -1 (-8175 2775)(-8625 2775);
WIRE 16 -1 (-8625 2775)(-8625 2900);
WIRE 16 -1 (-9075 2775)(-9075 2900);
WIRE 16 -1 (-7725 2775)(-8175 2775);
WIRE 16 -1 (-8175 2775)(-8175 2900);
WIRE 16 -1 (-7275 2775)(-7725 2775);
WIRE 16 -1 (-7725 2775)(-7725 2900);
WIRE 16 -1 (-6825 2775)(-7275 2775);
WIRE 16 -1 (-7275 2775)(-7275 2900);
WIRE 16 -1 (-6375 2775)(-6825 2775);
WIRE 16 -1 (-6825 2775)(-6825 2900);
WIRE 16 -1 (-5925 2775)(-6375 2775);
WIRE 16 -1 (-6375 2775)(-6375 2900);
WIRE 16 -1 (-5475 2775)(-5925 2775);
WIRE 16 -1 (-5925 2775)(-5925 2900);
WIRE 16 -1 (-5075 2775)(-5475 2775);
WIRE 16 -1 (-5475 2775)(-5475 2900);
WIRE 16 -1 (-5075 2775)(-5075 2900);
WIRE 16 -1 (-5075 2675)(-5075 2775);
WIRE 16 -1 (-5075 2400)(-5075 2475);
WIRE 16 -1 (-5075 2475)(-5475 2475);
WIRE 16 -1 (-5475 2475)(-5475 2400);
WIRE 16 -1 (-5475 2475)(-5925 2475);
WIRE 16 -1 (-5925 2400)(-5925 2475);
WIRE 16 -1 (-5925 2475)(-6375 2475);
WIRE 16 -1 (-6375 2400)(-6375 2475);
WIRE 16 -1 (-6375 2475)(-6825 2475);
WIRE 16 -1 (-6825 2475)(-6825 2400);
WIRE 16 -1 (-6825 2475)(-7275 2475);
WIRE 16 -1 (-7275 2400)(-7275 2475);
WIRE 16 -1 (-7275 2475)(-7725 2475);
WIRE 16 -1 (-7725 2400)(-7725 2475);
WIRE 16 -1 (-7725 2475)(-8175 2475);
WIRE 16 -1 (-8175 2475)(-8175 2400);
WIRE 16 -1 (-8175 2475)(-8625 2475);
WIRE 16 -1 (-8625 2475)(-9075 2475);
WIRE 16 -1 (-8625 2400)(-8625 2475);
WIRE 16 -1 (-9075 2475)(-9075 2525);
WIRE 16 -1 (-9075 2475)(-9075 2400);
WIRE 16 -1 (-8625 2075)(-9075 2075);
WIRE 16 -1 (-8175 2075)(-8625 2075);
WIRE 16 -1 (-8625 2075)(-8625 2200);
WIRE 16 -1 (-9075 2075)(-9075 2200);
WIRE 16 -1 (-7725 2075)(-8175 2075);
WIRE 16 -1 (-8175 2075)(-8175 2200);
WIRE 16 -1 (-7275 2075)(-7725 2075);
WIRE 16 -1 (-7725 2075)(-7725 2200);
WIRE 16 -1 (-6825 2075)(-7275 2075);
WIRE 16 -1 (-7275 2075)(-7275 2200);
WIRE 16 -1 (-6375 2075)(-6825 2075);
WIRE 16 -1 (-6825 2075)(-6825 2200);
WIRE 16 -1 (-5925 2075)(-6375 2075);
WIRE 16 -1 (-6375 2075)(-6375 2200);
WIRE 16 -1 (-5475 2075)(-5925 2075);
WIRE 16 -1 (-5925 2075)(-5925 2200);
WIRE 16 -1 (-5075 2075)(-5475 2075);
WIRE 16 -1 (-5475 2075)(-5475 2200);
WIRE 16 -1 (-5075 1975)(-5075 2075);
WIRE 16 -1 (-5075 2075)(-5075 2200);
WIRE 16 -1 (-5075 3825)(-5075 3900);
WIRE 16 -1 (-5075 3900)(-5475 3900);
WIRE 16 -1 (-5475 3900)(-5475 3825);
WIRE 16 -1 (-5475 3900)(-5925 3900);
WIRE 16 -1 (-5925 3825)(-5925 3900);
WIRE 16 -1 (-5925 3900)(-6375 3900);
WIRE 16 -1 (-6375 3825)(-6375 3900);
WIRE 16 -1 (-6375 3900)(-6825 3900);
WIRE 16 -1 (-6825 3900)(-6825 3825);
WIRE 16 -1 (-6825 3900)(-7275 3900);
WIRE 16 -1 (-7275 3825)(-7275 3900);
WIRE 16 -1 (-7275 3900)(-7725 3900);
WIRE 16 -1 (-7725 3825)(-7725 3900);
WIRE 16 -1 (-7725 3900)(-8175 3900);
WIRE 16 -1 (-8175 3900)(-8175 3825);
WIRE 16 -1 (-8175 3900)(-8625 3900);
WIRE 16 -1 (-8625 3900)(-9075 3900);
WIRE 16 -1 (-8625 3825)(-8625 3900);
WIRE 16 -1 (-9075 3900)(-9075 3950);
WIRE 16 -1 (-9075 3900)(-9075 3825);
WIRE 16 -1 (-8625 3500)(-9075 3500);
WIRE 16 -1 (-8175 3500)(-8625 3500);
WIRE 16 -1 (-8625 3500)(-8625 3625);
WIRE 16 -1 (-9075 3500)(-9075 3625);
WIRE 16 -1 (-8175 3500)(-8175 3625);
WIRE 16 -1 (-7725 3500)(-8175 3500);
WIRE 16 -1 (-7275 3500)(-7725 3500);
WIRE 16 -1 (-7725 3500)(-7725 3625);
WIRE 16 -1 (-6825 3500)(-7275 3500);
WIRE 16 -1 (-7275 3500)(-7275 3625);
WIRE 16 -1 (-6375 3500)(-6825 3500);
WIRE 16 -1 (-6825 3500)(-6825 3625);
WIRE 16 -1 (-5925 3500)(-6375 3500);
WIRE 16 -1 (-6375 3500)(-6375 3625);
WIRE 16 -1 (-5475 3500)(-5925 3500);
WIRE 16 -1 (-5925 3500)(-5925 3625);
WIRE 16 -1 (-5075 3500)(-5475 3500);
WIRE 16 -1 (-5475 3500)(-5475 3625);
WIRE 16 -1 (-5075 3500)(-5075 3625);
WIRE 16 -1 (-5075 3400)(-5075 3500);
WIRE 16 -1 (-5075 3100)(-5075 3175);
WIRE 16 -1 (-5075 3175)(-5475 3175);
WIRE 16 -1 (-5475 3175)(-5475 3100);
WIRE 16 -1 (-5475 3175)(-5925 3175);
WIRE 16 -1 (-5925 3100)(-5925 3175);
WIRE 16 -1 (-5925 3175)(-6375 3175);
WIRE 16 -1 (-6375 3100)(-6375 3175);
WIRE 16 -1 (-6375 3175)(-6825 3175);
WIRE 16 -1 (-6825 3175)(-6825 3100);
WIRE 16 -1 (-6825 3175)(-7275 3175);
WIRE 16 -1 (-7275 3100)(-7275 3175);
WIRE 16 -1 (-7275 3175)(-7725 3175);
WIRE 16 -1 (-7725 3100)(-7725 3175);
WIRE 16 -1 (-7725 3175)(-8175 3175);
WIRE 16 -1 (-8175 3175)(-8175 3100);
WIRE 16 -1 (-8175 3175)(-8625 3175);
WIRE 16 -1 (-8625 3175)(-9075 3175);
WIRE 16 -1 (-8625 3100)(-8625 3175);
WIRE 16 -1 (-9075 3175)(-9075 3225);
WIRE 16 -1 (-9075 3175)(-9075 3100);
WIRE 16 -1 (-8650 4925)(-9100 4925);
WIRE 16 -1 (-8200 4925)(-8650 4925);
WIRE 16 -1 (-8650 4925)(-8650 5050);
WIRE 16 -1 (-9100 4925)(-9100 5050);
WIRE 16 -1 (-7750 4925)(-8200 4925);
WIRE 16 -1 (-8200 4925)(-8200 5050);
WIRE 16 -1 (-7300 4925)(-7750 4925);
WIRE 16 -1 (-7750 4925)(-7750 5050);
WIRE 16 -1 (-6850 4925)(-7300 4925);
WIRE 16 -1 (-7300 4925)(-7300 5050);
WIRE 16 -1 (-6400 4925)(-6850 4925);
WIRE 16 -1 (-6850 4925)(-6850 5050);
WIRE 16 -1 (-5950 4925)(-6400 4925);
WIRE 16 -1 (-6400 4925)(-6400 5050);
WIRE 16 -1 (-5500 4925)(-5950 4925);
WIRE 16 -1 (-5950 4925)(-5950 5050);
WIRE 16 -1 (-5100 4925)(-5500 4925);
WIRE 16 -1 (-5500 4925)(-5500 5050);
WIRE 16 -1 (-5100 4925)(-5100 5050);
WIRE 16 -1 (-5100 4825)(-5100 4925);
WIRE 16 -1 (-5100 4525)(-5100 4600);
WIRE 16 -1 (-5100 4600)(-5500 4600);
WIRE 16 -1 (-5500 4600)(-5500 4525);
WIRE 16 -1 (-5500 4600)(-5950 4600);
WIRE 16 -1 (-5950 4525)(-5950 4600);
WIRE 16 -1 (-5950 4600)(-6400 4600);
WIRE 16 -1 (-6400 4525)(-6400 4600);
WIRE 16 -1 (-6400 4600)(-6850 4600);
WIRE 16 -1 (-6850 4600)(-6850 4525);
WIRE 16 -1 (-6850 4600)(-7300 4600);
WIRE 16 -1 (-7300 4525)(-7300 4600);
WIRE 16 -1 (-7300 4600)(-7750 4600);
WIRE 16 -1 (-7750 4525)(-7750 4600);
WIRE 16 -1 (-7750 4600)(-8200 4600);
WIRE 16 -1 (-8200 4600)(-8200 4525);
WIRE 16 -1 (-8200 4600)(-8650 4600);
WIRE 16 -1 (-8650 4600)(-9100 4600);
WIRE 16 -1 (-8650 4525)(-8650 4600);
WIRE 16 -1 (-9100 4600)(-9100 4650);
WIRE 16 -1 (-9100 4600)(-9100 4525);
WIRE 16 -1 (-8650 4200)(-9100 4200);
WIRE 16 -1 (-8200 4200)(-8650 4200);
WIRE 16 -1 (-8650 4200)(-8650 4325);
WIRE 16 -1 (-9100 4200)(-9100 4325);
WIRE 16 -1 (-7750 4200)(-8200 4200);
WIRE 16 -1 (-8200 4200)(-8200 4325);
WIRE 16 -1 (-7300 4200)(-7750 4200);
WIRE 16 -1 (-7750 4200)(-7750 4325);
WIRE 16 -1 (-6850 4200)(-7300 4200);
WIRE 16 -1 (-7300 4200)(-7300 4325);
WIRE 16 -1 (-6400 4200)(-6850 4200);
WIRE 16 -1 (-6850 4200)(-6850 4325);
WIRE 16 -1 (-5950 4200)(-6400 4200);
WIRE 16 -1 (-6400 4200)(-6400 4325);
WIRE 16 -1 (-5500 4200)(-5950 4200);
WIRE 16 -1 (-5950 4200)(-5950 4325);
WIRE 16 -1 (-5100 4200)(-5500 4200);
WIRE 16 -1 (-5500 4200)(-5500 4325);
WIRE 16 -1 (-5100 4100)(-5100 4200);
WIRE 16 -1 (-5100 4200)(-5100 4325);
WIRE 16 -1 (-5100 5250)(-5100 5325);
WIRE 16 -1 (-5100 5325)(-5500 5325);
WIRE 16 -1 (-5500 5325)(-5500 5250);
WIRE 16 -1 (-5500 5325)(-5950 5325);
WIRE 16 -1 (-5950 5250)(-5950 5325);
WIRE 16 -1 (-5950 5325)(-6400 5325);
WIRE 16 -1 (-6400 5250)(-6400 5325);
WIRE 16 -1 (-6400 5325)(-6850 5325);
WIRE 16 -1 (-6850 5325)(-6850 5250);
WIRE 16 -1 (-6850 5325)(-7300 5325);
WIRE 16 -1 (-7300 5250)(-7300 5325);
WIRE 16 -1 (-7300 5325)(-7750 5325);
WIRE 16 -1 (-7750 5250)(-7750 5325);
WIRE 16 -1 (-7750 5325)(-8200 5325);
WIRE 16 -1 (-8200 5325)(-8200 5250);
WIRE 16 -1 (-8200 5325)(-8650 5325);
WIRE 16 -1 (-8650 5325)(-9100 5325);
WIRE 16 -1 (-8650 5250)(-8650 5325);
WIRE 16 -1 (-9100 5325)(-9100 5375);
WIRE 16 -1 (-9100 5325)(-9100 5250);
WIRE 16 -1 (-5100 6000)(-5100 6075);
WIRE 16 -1 (-5100 6075)(-5500 6075);
WIRE 16 -1 (-5500 6075)(-5500 6000);
WIRE 16 -1 (-5500 6075)(-5950 6075);
WIRE 16 -1 (-5950 6000)(-5950 6075);
WIRE 16 -1 (-5950 6075)(-6400 6075);
WIRE 16 -1 (-6400 6000)(-6400 6075);
WIRE 16 -1 (-6400 6075)(-6850 6075);
WIRE 16 -1 (-6850 6075)(-6850 6000);
WIRE 16 -1 (-6850 6075)(-7300 6075);
WIRE 16 -1 (-7300 6000)(-7300 6075);
WIRE 16 -1 (-7300 6075)(-7750 6075);
WIRE 16 -1 (-7750 6000)(-7750 6075);
WIRE 16 -1 (-7750 6075)(-8200 6075);
WIRE 16 -1 (-8200 6075)(-8200 6000);
WIRE 16 -1 (-8200 6075)(-8650 6075);
WIRE 16 -1 (-8650 6075)(-9100 6075);
WIRE 16 -1 (-8650 6000)(-8650 6075);
WIRE 16 -1 (-9100 6075)(-9100 6125);
WIRE 16 -1 (-9100 6075)(-9100 6000);
WIRE 16 -1 (-8650 5675)(-9100 5675);
WIRE 16 -1 (-8200 5675)(-8650 5675);
WIRE 16 -1 (-8650 5675)(-8650 5800);
WIRE 16 -1 (-9100 5675)(-9100 5800);
WIRE 16 -1 (-7750 5675)(-8200 5675);
WIRE 16 -1 (-8200 5675)(-8200 5800);
WIRE 16 -1 (-7300 5675)(-7750 5675);
WIRE 16 -1 (-7750 5675)(-7750 5800);
WIRE 16 -1 (-6850 5675)(-7300 5675);
WIRE 16 -1 (-7300 5675)(-7300 5800);
WIRE 16 -1 (-6400 5675)(-6850 5675);
WIRE 16 -1 (-6850 5675)(-6850 5800);
WIRE 16 -1 (-5950 5675)(-6400 5675);
WIRE 16 -1 (-6400 5675)(-6400 5800);
WIRE 16 -1 (-5500 5675)(-5950 5675);
WIRE 16 -1 (-5950 5675)(-5950 5800);
WIRE 16 -1 (-5100 5675)(-5500 5675);
WIRE 16 -1 (-5500 5675)(-5500 5800);
WIRE 16 -1 (-5100 5675)(-5100 5800);
WIRE 16 -1 (-5100 5575)(-5100 5675);
WIRE 16 3135 (-9275 450)(-4725 450);
WIRE 16 3135 (-9275 450)(-9275 6550);
WIRE 16 3135 (-4725 450)(-4725 6550);
WIRE 16 3135 (-9275 6550)(-4725 6550);
WIRE 16 -1 (-500 3375)(-500 3450);
WIRE 16 -1 (-500 3450)(-900 3450);
WIRE 16 -1 (-900 3450)(-900 3375);
WIRE 16 -1 (-900 3450)(-1350 3450);
WIRE 16 -1 (-1350 3375)(-1350 3450);
WIRE 16 -1 (-1350 3450)(-1800 3450);
WIRE 16 -1 (-1800 3375)(-1800 3450);
WIRE 16 -1 (-1800 3450)(-2250 3450);
WIRE 16 -1 (-2250 3450)(-2250 3375);
WIRE 16 -1 (-2250 3450)(-2700 3450);
WIRE 16 -1 (-2700 3375)(-2700 3450);
WIRE 16 -1 (-2700 3450)(-3150 3450);
WIRE 16 -1 (-3150 3375)(-3150 3450);
WIRE 16 -1 (-3150 3450)(-3600 3450);
WIRE 16 -1 (-3600 3450)(-3600 3375);
WIRE 16 -1 (-3600 3450)(-4050 3450);
WIRE 16 -1 (-4050 3450)(-4500 3450);
WIRE 16 -1 (-4050 3375)(-4050 3450);
WIRE 16 -1 (-4500 3450)(-4500 3500);
WIRE 16 -1 (-4500 3450)(-4500 3375);
WIRE 16 -1 (-4050 3050)(-4500 3050);
WIRE 16 -1 (-4050 3050)(-4050 3175);
WIRE 16 -1 (-3600 3050)(-4050 3050);
WIRE 16 -1 (-4500 3050)(-4500 3175);
WIRE 16 -1 (-3600 3050)(-3600 3175);
WIRE 16 -1 (-3150 3050)(-3600 3050);
WIRE 16 -1 (-2700 3050)(-3150 3050);
WIRE 16 -1 (-3150 3050)(-3150 3175);
WIRE 16 -1 (-2700 3050)(-2700 3175);
WIRE 16 -1 (-2250 3050)(-2700 3050);
WIRE 16 -1 (-1800 3050)(-2250 3050);
WIRE 16 -1 (-2250 3050)(-2250 3175);
WIRE 16 -1 (-1800 3050)(-1800 3175);
WIRE 16 -1 (-1350 3050)(-1800 3050);
WIRE 16 -1 (-900 3050)(-1350 3050);
WIRE 16 -1 (-1350 3050)(-1350 3175);
WIRE 16 -1 (-900 3050)(-900 3175);
WIRE 16 -1 (-500 3050)(-900 3050);
WIRE 16 -1 (-500 3050)(-500 3175);
WIRE 16 -1 (-500 2950)(-500 3050);
WIRE 16 -1 (-500 2725)(-500 2800);
WIRE 16 -1 (-500 2800)(-900 2800);
WIRE 16 -1 (-900 2800)(-900 2725);
WIRE 16 -1 (-900 2800)(-1350 2800);
WIRE 16 -1 (-1350 2725)(-1350 2800);
WIRE 16 -1 (-1350 2800)(-1800 2800);
WIRE 16 -1 (-1800 2725)(-1800 2800);
WIRE 16 -1 (-1800 2800)(-2250 2800);
WIRE 16 -1 (-2250 2800)(-2250 2725);
WIRE 16 -1 (-2250 2800)(-2700 2800);
WIRE 16 -1 (-2700 2725)(-2700 2800);
WIRE 16 -1 (-2700 2800)(-3150 2800);
WIRE 16 -1 (-3150 2725)(-3150 2800);
WIRE 16 -1 (-3150 2800)(-3600 2800);
WIRE 16 -1 (-3600 2800)(-3600 2725);
WIRE 16 -1 (-3600 2800)(-4050 2800);
WIRE 16 -1 (-4050 2800)(-4500 2800);
WIRE 16 -1 (-4050 2725)(-4050 2800);
WIRE 16 -1 (-4500 2800)(-4500 2850);
WIRE 16 -1 (-4500 2800)(-4500 2725);
WIRE 16 -1 (-4050 2400)(-4500 2400);
WIRE 16 -1 (-3600 2400)(-4050 2400);
WIRE 16 -1 (-4050 2400)(-4050 2525);
WIRE 16 -1 (-4500 2400)(-4500 2525);
WIRE 16 -1 (-3150 2400)(-3600 2400);
WIRE 16 -1 (-3600 2400)(-3600 2525);
WIRE 16 -1 (-2700 2400)(-3150 2400);
WIRE 16 -1 (-3150 2400)(-3150 2525);
WIRE 16 -1 (-2250 2400)(-2700 2400);
WIRE 16 -1 (-2700 2400)(-2700 2525);
WIRE 16 -1 (-1800 2400)(-2250 2400);
WIRE 16 -1 (-2250 2400)(-2250 2525);
WIRE 16 -1 (-1350 2400)(-1800 2400);
WIRE 16 -1 (-1800 2400)(-1800 2525);
WIRE 16 -1 (-900 2400)(-1350 2400);
WIRE 16 -1 (-1350 2400)(-1350 2525);
WIRE 16 -1 (-500 2400)(-900 2400);
WIRE 16 -1 (-900 2400)(-900 2525);
WIRE 16 -1 (-500 2325)(-500 2400);
WIRE 16 -1 (-500 2400)(-500 2525);
WIRE 16 -1 (-500 2100)(-500 2175);
WIRE 16 -1 (-500 2175)(-900 2175);
WIRE 16 -1 (-900 2175)(-900 2100);
WIRE 16 -1 (-900 2175)(-1350 2175);
WIRE 16 -1 (-1350 2100)(-1350 2175);
WIRE 16 -1 (-1350 2175)(-1800 2175);
WIRE 16 -1 (-1800 2100)(-1800 2175);
WIRE 16 -1 (-1800 2175)(-2250 2175);
WIRE 16 -1 (-2250 2175)(-2250 2100);
WIRE 16 -1 (-2250 2175)(-2700 2175);
WIRE 16 -1 (-2700 2100)(-2700 2175);
WIRE 16 -1 (-2700 2175)(-3150 2175);
WIRE 16 -1 (-3150 2100)(-3150 2175);
WIRE 16 -1 (-3150 2175)(-3600 2175);
WIRE 16 -1 (-3600 2175)(-3600 2100);
WIRE 16 -1 (-3600 2175)(-4050 2175);
WIRE 16 -1 (-4050 2175)(-4500 2175);
WIRE 16 -1 (-4050 2100)(-4050 2175);
WIRE 16 -1 (-4500 2175)(-4500 2225);
WIRE 16 -1 (-4500 2175)(-4500 2100);
WIRE 16 -1 (-4050 1775)(-4500 1775);
WIRE 16 -1 (-3600 1775)(-4050 1775);
WIRE 16 -1 (-4050 1775)(-4050 1900);
WIRE 16 -1 (-4500 1775)(-4500 1900);
WIRE 16 -1 (-3150 1775)(-3600 1775);
WIRE 16 -1 (-3600 1775)(-3600 1900);
WIRE 16 -1 (-2700 1775)(-3150 1775);
WIRE 16 -1 (-3150 1775)(-3150 1900);
WIRE 16 -1 (-2250 1775)(-2700 1775);
WIRE 16 -1 (-2700 1775)(-2700 1900);
WIRE 16 -1 (-1800 1775)(-2250 1775);
WIRE 16 -1 (-2250 1775)(-2250 1900);
WIRE 16 -1 (-1350 1775)(-1800 1775);
WIRE 16 -1 (-1800 1775)(-1800 1900);
WIRE 16 -1 (-900 1775)(-1350 1775);
WIRE 16 -1 (-1350 1775)(-1350 1900);
WIRE 16 -1 (-500 1775)(-900 1775);
WIRE 16 -1 (-900 1775)(-900 1900);
WIRE 16 -1 (-500 1775)(-500 1900);
WIRE 16 -1 (-500 1675)(-500 1775);
WIRE 16 -1 (-500 1500)(-500 1575);
WIRE 16 -1 (-500 1575)(-900 1575);
WIRE 16 -1 (-900 1575)(-900 1500);
WIRE 16 -1 (-900 1575)(-1350 1575);
WIRE 16 -1 (-1350 1500)(-1350 1575);
WIRE 16 -1 (-1350 1575)(-1800 1575);
WIRE 16 -1 (-1800 1500)(-1800 1575);
WIRE 16 -1 (-1800 1575)(-2250 1575);
WIRE 16 -1 (-2250 1575)(-2250 1500);
WIRE 16 -1 (-2250 1575)(-2700 1575);
WIRE 16 -1 (-2700 1500)(-2700 1575);
WIRE 16 -1 (-2700 1575)(-3150 1575);
WIRE 16 -1 (-3150 1500)(-3150 1575);
WIRE 16 -1 (-3150 1575)(-3600 1575);
WIRE 16 -1 (-3600 1575)(-4050 1575);
WIRE 16 -1 (-3600 1575)(-3600 1500);
WIRE 16 -1 (-4050 1575)(-4500 1575);
WIRE 16 -1 (-4050 1500)(-4050 1575);
WIRE 16 -1 (-4500 1575)(-4500 1625);
WIRE 16 -1 (-4500 1575)(-4500 1500);
WIRE 16 -1 (-4050 1175)(-4500 1175);
WIRE 16 -1 (-3600 1175)(-4050 1175);
WIRE 16 -1 (-4050 1175)(-4050 1300);
WIRE 16 -1 (-4500 1175)(-4500 1300);
WIRE 16 -1 (-3150 1175)(-3600 1175);
WIRE 16 -1 (-3600 1175)(-3600 1300);
WIRE 16 -1 (-2700 1175)(-3150 1175);
WIRE 16 -1 (-3150 1175)(-3150 1300);
WIRE 16 -1 (-2250 1175)(-2700 1175);
WIRE 16 -1 (-2700 1175)(-2700 1300);
WIRE 16 -1 (-1800 1175)(-2250 1175);
WIRE 16 -1 (-2250 1175)(-2250 1300);
WIRE 16 -1 (-1350 1175)(-1800 1175);
WIRE 16 -1 (-1800 1175)(-1800 1300);
WIRE 16 -1 (-900 1175)(-1350 1175);
WIRE 16 -1 (-1350 1300)(-1350 1175);
WIRE 16 -1 (-500 1175)(-900 1175);
WIRE 16 -1 (-900 1175)(-900 1300);
WIRE 16 -1 (-500 1175)(-500 1300);
WIRE 16 -1 (-500 1075)(-500 1175);
WIRE 16 -1 (-4050 975)(-4500 975);
WIRE 16 -1 (-4050 900)(-4050 975);
WIRE 16 -1 (-4500 975)(-4500 1025);
WIRE 16 -1 (-4500 975)(-4500 900);
WIRE 16 -1 (-4050 575)(-4500 575);
WIRE 16 -1 (-4050 525)(-4050 575);
WIRE 16 -1 (-4050 575)(-4050 700);
WIRE 16 -1 (-4500 575)(-4500 700);
WIRE 16 -1 (-525 5200)(-525 5275);
WIRE 16 -1 (-525 5275)(-925 5275);
WIRE 16 -1 (-925 5275)(-925 5200);
WIRE 16 -1 (-925 5275)(-1375 5275);
WIRE 16 -1 (-1375 5200)(-1375 5275);
WIRE 16 -1 (-1375 5275)(-1825 5275);
WIRE 16 -1 (-1825 5200)(-1825 5275);
WIRE 16 -1 (-1825 5275)(-2275 5275);
WIRE 16 -1 (-2275 5275)(-2275 5200);
WIRE 16 -1 (-2275 5275)(-2725 5275);
WIRE 16 -1 (-2725 5200)(-2725 5275);
WIRE 16 -1 (-2725 5275)(-3175 5275);
WIRE 16 -1 (-3175 5200)(-3175 5275);
WIRE 16 -1 (-3175 5275)(-3625 5275);
WIRE 16 -1 (-3625 5275)(-3625 5200);
WIRE 16 -1 (-3625 5275)(-4075 5275);
WIRE 16 -1 (-4075 5275)(-4525 5275);
WIRE 16 -1 (-4075 5200)(-4075 5275);
WIRE 16 -1 (-4525 5275)(-4525 5325);
WIRE 16 -1 (-4525 5275)(-4525 5200);
WIRE 16 -1 (-4075 4875)(-4525 4875);
WIRE 16 -1 (-3625 4875)(-4075 4875);
WIRE 16 -1 (-4075 4875)(-4075 5000);
WIRE 16 -1 (-4525 4875)(-4525 5000);
WIRE 16 -1 (-3175 4875)(-3625 4875);
WIRE 16 -1 (-3625 4875)(-3625 5000);
WIRE 16 -1 (-2725 4875)(-3175 4875);
WIRE 16 -1 (-3175 4875)(-3175 5000);
WIRE 16 -1 (-2275 4875)(-2725 4875);
WIRE 16 -1 (-2725 4875)(-2725 5000);
WIRE 16 -1 (-1825 4875)(-2275 4875);
WIRE 16 -1 (-2275 4875)(-2275 5000);
WIRE 16 -1 (-1375 4875)(-1825 4875);
WIRE 16 -1 (-1825 4875)(-1825 5000);
WIRE 16 -1 (-925 4875)(-1375 4875);
WIRE 16 -1 (-1375 4875)(-1375 5000);
WIRE 16 -1 (-525 4875)(-925 4875);
WIRE 16 -1 (-925 4875)(-925 5000);
WIRE 16 -1 (-525 4775)(-525 4875);
WIRE 16 -1 (-525 4875)(-525 5000);
WIRE 16 -1 (-525 6000)(-525 6075);
WIRE 16 -1 (-525 6075)(-925 6075);
WIRE 16 -1 (-925 6075)(-925 6000);
WIRE 16 -1 (-925 6075)(-1375 6075);
WIRE 16 -1 (-1375 6000)(-1375 6075);
WIRE 16 -1 (-1375 6075)(-1825 6075);
WIRE 16 -1 (-1825 6000)(-1825 6075);
WIRE 16 -1 (-1825 6075)(-2275 6075);
WIRE 16 -1 (-2275 6075)(-2275 6000);
WIRE 16 -1 (-2275 6075)(-2725 6075);
WIRE 16 -1 (-2725 6000)(-2725 6075);
WIRE 16 -1 (-2725 6075)(-3175 6075);
WIRE 16 -1 (-3175 6000)(-3175 6075);
WIRE 16 -1 (-3175 6075)(-3625 6075);
WIRE 16 -1 (-3625 6075)(-3625 6000);
WIRE 16 -1 (-3625 6075)(-4075 6075);
WIRE 16 -1 (-4075 6075)(-4525 6075);
WIRE 16 -1 (-4075 6000)(-4075 6075);
WIRE 16 -1 (-4525 6075)(-4525 6125);
WIRE 16 -1 (-4525 6075)(-4525 6000);
WIRE 16 -1 (-4075 5675)(-4525 5675);
WIRE 16 -1 (-3625 5675)(-4075 5675);
WIRE 16 -1 (-4075 5675)(-4075 5800);
WIRE 16 -1 (-4525 5675)(-4525 5800);
WIRE 16 -1 (-3175 5675)(-3625 5675);
WIRE 16 -1 (-3625 5675)(-3625 5800);
WIRE 16 -1 (-2725 5675)(-3175 5675);
WIRE 16 -1 (-3175 5675)(-3175 5800);
WIRE 16 -1 (-2275 5675)(-2725 5675);
WIRE 16 -1 (-2725 5675)(-2725 5800);
WIRE 16 -1 (-1825 5675)(-2275 5675);
WIRE 16 -1 (-2275 5675)(-2275 5800);
WIRE 16 -1 (-1375 5675)(-1825 5675);
WIRE 16 -1 (-1825 5675)(-1825 5800);
WIRE 16 -1 (-925 5675)(-1375 5675);
WIRE 16 -1 (-1375 5675)(-1375 5800);
WIRE 16 -1 (-525 5675)(-925 5675);
WIRE 16 -1 (-925 5675)(-925 5800);
WIRE 16 -1 (-525 5575)(-525 5675);
WIRE 16 -1 (-525 5675)(-525 5800);
WIRE 16 -1 (-4050 4500)(-4500 4500);
WIRE 16 -1 (-3600 4500)(-4050 4500);
WIRE 16 -1 (-4050 4425)(-4050 4500);
WIRE 16 -1 (-4500 4500)(-4500 4550);
WIRE 16 -1 (-4500 4500)(-4500 4425);
WIRE 16 -1 (-3150 4500)(-3600 4500);
WIRE 16 -1 (-3600 4500)(-3600 4425);
WIRE 16 -1 (-3150 4425)(-3150 4500);
WIRE 16 -1 (-4050 4100)(-4500 4100);
WIRE 16 -1 (-3600 4100)(-4050 4100);
WIRE 16 -1 (-4050 4100)(-4050 4225);
WIRE 16 -1 (-4500 4100)(-4500 4225);
WIRE 16 -1 (-3150 4100)(-3600 4100);
WIRE 16 -1 (-3600 4100)(-3600 4225);
WIRE 16 -1 (-3150 4000)(-3150 4100);
WIRE 16 -1 (-3150 4100)(-3150 4225);
WIRE 16 3135 (-4650 3825)(-200 3825);
WIRE 16 3135 (-4650 3825)(-4650 6500);
WIRE 16 3135 (-200 3825)(-200 6500);
WIRE 16 3135 (-4650 6500)(-200 6500);
DOT 1 (-8650 4600);
DOT 1 (-4050 2175);
DOT 1 (-3600 3450);
DOT 1 (-9075 1050);
DOT 1 (-8625 650);
DOT 1 (-8625 1050);
DOT 1 (-9075 1750);
DOT 1 (-8625 1350);
DOT 1 (-8625 1750);
DOT 1 (-8625 2075);
DOT 1 (-9075 2475);
DOT 1 (-8625 2475);
DOT 1 (-8625 2775);
DOT 1 (-8625 3175);
DOT 1 (-9075 3175);
DOT 1 (-9075 3900);
DOT 1 (-8625 3500);
DOT 1 (-8625 3900);
DOT 1 (-8650 4200);
DOT 1 (-9100 4600);
DOT 1 (-8650 4925);
DOT 1 (-9100 5325);
DOT 1 (-9100 6075);
DOT 1 (-8650 5325);
DOT 1 (-8650 5675);
DOT 1 (-8650 6075);
DOT 1 (-8175 650);
DOT 1 (-8175 1050);
DOT 1 (-7725 650);
DOT 1 (-7725 1050);
DOT 1 (-7275 650);
DOT 1 (-7275 1050);
DOT 1 (-8175 1350);
DOT 1 (-8175 1750);
DOT 1 (-8175 2075);
DOT 1 (-7725 1350);
DOT 1 (-7275 1350);
DOT 1 (-7725 1750);
DOT 1 (-7725 2075);
DOT 1 (-7275 2075);
DOT 1 (-7275 1750);
DOT 1 (-6825 650);
DOT 1 (-6825 1050);
DOT 1 (-6375 650);
DOT 1 (-6825 1350);
DOT 1 (-6825 1750);
DOT 1 (-6825 2075);
DOT 1 (-6375 1350);
DOT 1 (-6375 1750);
DOT 1 (-6375 2075);
DOT 1 (-8175 2475);
DOT 1 (-8175 2775);
DOT 1 (-7725 2475);
DOT 1 (-7275 2475);
DOT 1 (-7725 2775);
DOT 1 (-7275 2775);
DOT 1 (-7275 3175);
DOT 1 (-7725 3175);
DOT 1 (-8175 3175);
DOT 1 (-8175 3500);
DOT 1 (-8175 3900);
DOT 1 (-7725 3500);
DOT 1 (-7275 3500);
DOT 1 (-7725 3900);
DOT 1 (-7275 3900);
DOT 1 (-6825 2475);
DOT 1 (-6825 2775);
DOT 1 (-6375 2475);
DOT 1 (-6375 2775);
DOT 1 (-6375 3175);
DOT 1 (-6825 3175);
DOT 1 (-6825 3500);
DOT 1 (-6825 3900);
DOT 1 (-6375 3500);
DOT 1 (-6375 3900);
DOT 1 (-5925 1350);
DOT 1 (-5925 1750);
DOT 1 (-5925 2075);
DOT 1 (-5475 1350);
DOT 1 (-5475 1750);
DOT 1 (-5475 2075);
DOT 1 (-4500 975);
DOT 1 (-5075 1350);
DOT 1 (-5075 2075);
DOT 1 (-4500 1575);
DOT 1 (-5925 2475);
DOT 1 (-5925 2775);
DOT 1 (-5475 2475);
DOT 1 (-5475 2775);
DOT 1 (-5475 3175);
DOT 1 (-5925 3175);
DOT 1 (-5925 3500);
DOT 1 (-5925 3900);
DOT 1 (-5475 3500);
DOT 1 (-5475 3900);
DOT 1 (-5075 2775);
DOT 1 (-4500 2175);
DOT 1 (-4500 2800);
DOT 1 (-5075 3500);
DOT 1 (-4500 3450);
DOT 1 (-5100 4200);
DOT 1 (-5500 4200);
DOT 1 (-5950 4200);
DOT 1 (-6400 4200);
DOT 1 (-6850 4200);
DOT 1 (-7300 4200);
DOT 1 (-7750 4200);
DOT 1 (-8200 4200);
DOT 1 (-8200 4600);
DOT 1 (-8200 4925);
DOT 1 (-7750 4600);
DOT 1 (-7300 4600);
DOT 1 (-7750 4925);
DOT 1 (-7300 4925);
DOT 1 (-8200 5325);
DOT 1 (-8200 5675);
DOT 1 (-8200 6075);
DOT 1 (-7750 5325);
DOT 1 (-7750 5675);
DOT 1 (-7300 5325);
DOT 1 (-7300 5675);
DOT 1 (-7750 6075);
DOT 1 (-7300 6075);
DOT 1 (-6850 4600);
DOT 1 (-6850 4925);
DOT 1 (-6400 4600);
DOT 1 (-6400 4925);
DOT 1 (-6850 5325);
DOT 1 (-6850 5675);
DOT 1 (-6850 6075);
DOT 1 (-6400 5325);
DOT 1 (-6400 5675);
DOT 1 (-6400 6075);
DOT 1 (-5950 4600);
DOT 1 (-5950 4925);
DOT 1 (-5500 4600);
DOT 1 (-5500 4925);
DOT 1 (-5950 5675);
DOT 1 (-5950 6075);
DOT 1 (-5500 5325);
DOT 1 (-5500 5675);
DOT 1 (-5500 6075);
DOT 1 (-5100 4925);
DOT 1 (-4500 4500);
DOT 1 (-5100 5675);
DOT 1 (-4525 5275);
DOT 1 (-4525 6075);
DOT 1 (-4050 575);
DOT 1 (-4050 1175);
DOT 1 (-4050 1575);
DOT 1 (-4050 1775);
DOT 1 (-3600 1175);
DOT 1 (-3600 1575);
DOT 1 (-3600 1775);
DOT 1 (-3150 1175);
DOT 1 (-3150 1575);
DOT 1 (-2700 1175);
DOT 1 (-2700 1575);
DOT 1 (-3150 1775);
DOT 1 (-2700 1775);
DOT 1 (-2250 1175);
DOT 1 (-2250 1575);
DOT 1 (-2250 1775);
DOT 1 (-4050 2400);
DOT 1 (-4050 2800);
DOT 1 (-4050 3050);
DOT 1 (-3600 2400);
DOT 1 (-3600 2175);
DOT 1 (-3600 2800);
DOT 1 (-3600 3050);
DOT 1 (-4050 3450);
DOT 1 (-4050 4100);
DOT 1 (-3600 4100);
DOT 1 (-3150 2175);
DOT 1 (-3150 2400);
DOT 1 (-2700 2175);
DOT 1 (-2700 2400);
DOT 1 (-3150 2800);
DOT 1 (-3150 3050);
DOT 1 (-2700 2800);
DOT 1 (-2700 3050);
DOT 1 (-2250 2175);
DOT 1 (-2250 2400);
DOT 1 (-2250 2800);
DOT 1 (-2250 3050);
DOT 1 (-3150 3450);
DOT 1 (-2700 3450);
DOT 1 (-3150 4100);
DOT 1 (-2250 3450);
DOT 1 (-1800 1175);
DOT 1 (-1800 1575);
DOT 1 (-1800 1775);
DOT 1 (-1350 1175);
DOT 1 (-1350 1575);
DOT 1 (-1350 1775);
DOT 1 (-900 1175);
DOT 1 (-900 1575);
DOT 1 (-900 1775);
DOT 1 (-500 1175);
DOT 1 (-500 1775);
DOT 1 (-1800 2400);
DOT 1 (-1800 2175);
DOT 1 (-1800 2800);
DOT 1 (-1800 3050);
DOT 1 (-1350 2175);
DOT 1 (-1350 2400);
DOT 1 (-1350 2800);
DOT 1 (-1350 3050);
DOT 1 (-1800 3450);
DOT 1 (-1350 3450);
DOT 1 (-900 2175);
DOT 1 (-900 2400);
DOT 1 (-900 2800);
DOT 1 (-900 3050);
DOT 1 (-500 2400);
DOT 1 (-500 3050);
DOT 1 (-900 3450);
DOT 1 (-4050 4500);
DOT 1 (-4075 4875);
DOT 1 (-3600 4500);
DOT 1 (-3625 4875);
DOT 1 (-3175 4875);
DOT 1 (-4075 5275);
DOT 1 (-4075 5675);
DOT 1 (-4075 6075);
DOT 1 (-3625 5275);
DOT 1 (-3625 5675);
DOT 1 (-3175 5275);
DOT 1 (-3175 5675);
DOT 1 (-3625 6075);
DOT 1 (-3175 6075);
DOT 1 (-2725 4875);
DOT 1 (-2275 4875);
DOT 1 (-2725 5275);
DOT 1 (-2725 5675);
DOT 1 (-2725 6075);
DOT 1 (-2275 5275);
DOT 1 (-2275 5675);
DOT 1 (-2275 6075);
DOT 1 (-1825 4875);
DOT 1 (-1375 4875);
DOT 1 (-1825 5275);
DOT 1 (-1825 5675);
DOT 1 (-1825 6075);
DOT 1 (-1375 5275);
DOT 1 (-1375 5675);
DOT 1 (-1375 6075);
DOT 1 (-925 4875);
DOT 1 (-525 4875);
DOT 1 (-925 5275);
DOT 1 (-925 5675);
DOT 1 (-925 6075);
DOT 1 (-525 5675);
DOT 1 (-5950 5325);
FORCENOTE
PVDD11_S3_P0: 42PCS 22UF ON BOT
(-4200 3575) 0;
DISPLAY LEFT (-4200 3575);
DISPLAY 2.510638 (-4200 3575);
PAINT WHITE (-4200 3575);
FORCENOTE
5
(-2725 3475) 0;
DISPLAY LEFT (-2725 3475);
DISPLAY 1.021277 (-2725 3475);
PAINT SKYBLUE (-2725 3475);
FORCENOTE
PVDDCR_SOC_P0: 77PCS 22UF ON BOT
(-9175 6325) 0;
DISPLAY LEFT (-9175 6325);
DISPLAY 2.510638 (-9175 6325);
PAINT WHITE (-9175 6325);
FORCENOTE
5
(-7300 1100) 0;
DISPLAY LEFT (-7300 1100);
DISPLAY 1.021277 (-7300 1100);
PAINT SKYBLUE (-7300 1100);
FORCENOTE
5
(-7300 1800) 0;
DISPLAY LEFT (-7300 1800);
DISPLAY 1.021277 (-7300 1800);
PAINT SKYBLUE (-7300 1800);
FORCENOTE
5
(-7300 3200) 0;
DISPLAY LEFT (-7300 3200);
DISPLAY 1.021277 (-7300 3200);
PAINT SKYBLUE (-7300 3200);
FORCENOTE
5
(-7300 3925) 0;
DISPLAY LEFT (-7300 3925);
DISPLAY 1.021277 (-7300 3925);
PAINT SKYBLUE (-7300 3925);
FORCENOTE
5
(-7300 2525) 0;
DISPLAY LEFT (-7300 2525);
DISPLAY 1.021277 (-7300 2525);
PAINT SKYBLUE (-7300 2525);
FORCENOTE
10
(-5125 1800) 0;
DISPLAY LEFT (-5125 1800);
DISPLAY 1.021277 (-5125 1800);
PAINT SKYBLUE (-5125 1800);
FORCENOTE
10
(-5125 2525) 0;
DISPLAY LEFT (-5125 2525);
DISPLAY 1.021277 (-5125 2525);
PAINT SKYBLUE (-5125 2525);
FORCENOTE
10
(-5100 3200) 0;
DISPLAY LEFT (-5100 3200);
DISPLAY 1.021277 (-5100 3200);
PAINT SKYBLUE (-5100 3200);
FORCENOTE
10
(-5125 3925) 0;
DISPLAY LEFT (-5125 3925);
DISPLAY 1.021277 (-5125 3925);
PAINT SKYBLUE (-5125 3925);
FORCENOTE
5
(-7325 4650) 0;
DISPLAY LEFT (-7325 4650);
DISPLAY 1.021277 (-7325 4650);
PAINT SKYBLUE (-7325 4650);
FORCENOTE
5
(-7325 6125) 0;
DISPLAY LEFT (-7325 6125);
DISPLAY 1.021277 (-7325 6125);
PAINT SKYBLUE (-7325 6125);
FORCENOTE
10
(-5150 4625) 0;
DISPLAY LEFT (-5150 4625);
DISPLAY 1.021277 (-5150 4625);
PAINT SKYBLUE (-5150 4625);
FORCENOTE
10
(-5150 6100) 0;
DISPLAY LEFT (-5150 6100);
DISPLAY 1.021277 (-5150 6100);
PAINT SKYBLUE (-5150 6100);
FORCENOTE
PVDDIO_P0: 24PCS 22UF ON BOT
(-4550 6325) 0;
DISPLAY LEFT (-4550 6325);
DISPLAY 2.510638 (-4550 6325);
PAINT WHITE (-4550 6325);
FORCENOTE
5
(-2725 1625) 0;
DISPLAY LEFT (-2725 1625);
DISPLAY 1.021277 (-2725 1625);
PAINT SKYBLUE (-2725 1625);
FORCENOTE
5
(-2725 2225) 0;
DISPLAY LEFT (-2725 2225);
DISPLAY 1.021277 (-2725 2225);
PAINT SKYBLUE (-2725 2225);
FORCENOTE
5
(-2725 2825) 0;
DISPLAY LEFT (-2725 2825);
DISPLAY 1.021277 (-2725 2825);
PAINT SKYBLUE (-2725 2825);
FORCENOTE
10
(-650 1600) 0;
DISPLAY LEFT (-650 1600);
DISPLAY 1.021277 (-650 1600);
PAINT SKYBLUE (-650 1600);
FORCENOTE
10
(-550 2200) 0;
DISPLAY LEFT (-550 2200);
DISPLAY 1.021277 (-550 2200);
PAINT SKYBLUE (-550 2200);
FORCENOTE
10
(-550 2825) 0;
DISPLAY LEFT (-550 2825);
DISPLAY 1.021277 (-550 2825);
PAINT SKYBLUE (-550 2825);
FORCENOTE
10
(-525 3475) 0;
DISPLAY LEFT (-525 3475);
DISPLAY 1.021277 (-525 3475);
PAINT SKYBLUE (-525 3475);
FORCENOTE
5
(-2750 5375) 0;
DISPLAY LEFT (-2750 5375);
DISPLAY 1.021277 (-2750 5375);
PAINT SKYBLUE (-2750 5375);
FORCENOTE
5
(-2750 6175) 0;
DISPLAY LEFT (-2750 6175);
DISPLAY 1.021277 (-2750 6175);
PAINT SKYBLUE (-2750 6175);
FORCENOTE
10
(-575 6175) 0;
DISPLAY LEFT (-575 6175);
DISPLAY 1.021277 (-575 6175);
PAINT SKYBLUE (-575 6175);
FORCENOTE
10
(-575 5375) 0;
DISPLAY LEFT (-575 5375);
DISPLAY 1.021277 (-575 5375);
PAINT SKYBLUE (-575 5375);
FORCENOTE
10
(-5150 5350) 0;
DISPLAY LEFT (-5150 5350);
DISPLAY 1.021277 (-5150 5350);
PAINT SKYBLUE (-5150 5350);
FORCENOTE
5
(-7325 5375) 0;
DISPLAY LEFT (-7325 5375);
DISPLAY 1.021277 (-7325 5375);
PAINT SKYBLUE (-7325 5375);
QUIT
